G04 ================== begin FILE IDENTIFICATION RECORD ==================*
G04 Layout Name:  15105-sa.brd*
G04 Film Name:    SE_REF_L6*
G04 File Format:  Gerber RS274X*
G04 File Origin:  Cadence Allegro 16.5-S056*
G04 Origin Date:  Wed Nov 16 02:02:44 2016*
G04 *
G04 Layer:  BOARD GEOMETRY/SE_REF_L6_TBL*
G04 Layer:  BOARD GEOMETRY/SE_REF_L6_L6*
G04 Layer:  BOARD GEOMETRY/PANEL_OUTLINE*
G04 *
G04 Offset:    (0.00 0.00)*
G04 Mirror:    No*
G04 Mode:      Positive*
G04 Rotation:  0*
G04 FullContactRelief:  No*
G04 UndefLineWidth:     6.00*
G04 ================== end FILE IDENTIFICATION RECORD ====================*
%FSLAX35Y35*MOIN*%
%IR0*IPPOS*OFA0.00000B0.00000*MIA0B0*SFA1.00000B1.00000*%
%ADD10C,.02*%
%ADD11C,.005*%
%ADD12C,.006*%
G75*
%LPD*%
G75*
G54D10*
G01X1479970Y793988D02*
X2197470D01*
G01X1479970Y863288D02*
Y793988D01*
G01Y828638D02*
X2197470D01*
G01X1479970Y863288D02*
X2197470D01*
G01X1654970D02*
Y793988D01*
G01X1882470Y863288D02*
Y793988D01*
G01X1987470Y863288D02*
Y793988D01*
G01X2197470Y863288D02*
Y793988D01*
G54D11*
G01X25350Y389000D02*
X25400D01*
G01D02*
X25200Y389200D01*
G01D02*
Y438335D01*
G01D02*
X20700Y442835D01*
G01D02*
Y708150D01*
G01X23720Y472640D02*
X22500Y473860D01*
G01D02*
Y657500D01*
G01X50279Y487421D02*
X24800Y512900D01*
G01D02*
Y540900D01*
G01X60982Y492164D02*
X27450Y525696D01*
G01D02*
Y669850D01*
G01X22500Y657500D02*
X24000Y659000D01*
G01X27450Y669850D02*
X26100Y671200D01*
G01X31150Y658211D02*
X29500Y659861D01*
G01D02*
Y676500D01*
G01X20700Y708150D02*
X25200Y712650D01*
G01X58700Y308600D02*
Y307383D01*
G01D02*
X64583Y301500D01*
G01X48700Y311117D02*
X49650Y310167D01*
G01D02*
Y308633D01*
G01D02*
X42358Y301341D01*
G01D02*
X42241D01*
G01D02*
X40400Y299500D01*
G01D02*
X39000D01*
G01X53900Y314250D02*
Y310061D01*
G01D02*
X64661Y299300D01*
G01X53100Y279500D02*
X52000Y280600D01*
G01D02*
Y311760D01*
G01X47200Y320900D02*
Y310000D01*
G01D02*
X47800Y309400D01*
G01X35300Y303100D02*
Y304000D01*
G01D02*
X41300Y310000D01*
G01D02*
Y316683D01*
G01X61400Y348574D02*
X56250Y343424D01*
G01D02*
Y331050D01*
G01D02*
X56450Y330850D01*
G01D02*
Y324433D01*
G01D02*
X51817Y319800D01*
G01D02*
X51011D01*
G01D02*
X48700Y317489D01*
G01D02*
Y311117D01*
G01X52050Y316100D02*
X53900Y314250D01*
G01X52000Y311760D02*
X50200Y313560D01*
G01D02*
Y316867D01*
G01D02*
X51633Y318300D01*
G01D02*
X55800D01*
G01D02*
X72651Y335151D01*
G01X59593Y348889D02*
X52150Y341446D01*
G01D02*
Y325850D01*
G01D02*
X47200Y320900D01*
G01X41300Y316683D02*
X41450Y316833D01*
G01D02*
Y318367D01*
G01D02*
X41300Y318517D01*
G01D02*
Y323300D01*
G01D02*
X48485Y330485D01*
G01D02*
Y341386D01*
G01D02*
X51559Y344460D01*
G01X75384Y391100D02*
X61400Y377116D01*
G01D02*
Y348574D01*
G01X72651Y344809D02*
X63500Y353960D01*
G01X54200Y347400D02*
X55982D01*
G01D02*
X58093Y349511D01*
G01D02*
Y354607D01*
G01D02*
X49900Y362800D01*
G01D02*
Y456700D01*
G01X56787Y389202D02*
Y358035D01*
G01D02*
X59593Y355229D01*
G01D02*
Y348889D01*
G01X51559Y344460D02*
Y349395D01*
G01D02*
X52521Y350357D01*
G01X70985Y403400D02*
X56787Y389202D01*
G01X63946Y393500D02*
X62838Y392392D01*
G01X46087Y455819D02*
X44650Y457256D01*
G01D02*
Y461067D01*
G01D02*
X47383Y463800D01*
G01D02*
X48359D01*
G01D02*
X50279Y465720D01*
G01D02*
Y475412D01*
G01D02*
X51541Y476674D01*
G01D02*
Y479033D01*
G01D02*
X51662Y479154D01*
G01X49900Y456700D02*
X46500Y460100D01*
G01D02*
Y460300D01*
G01X51662Y479154D02*
Y480688D01*
G01D02*
X50279Y482071D01*
G01D02*
Y487421D01*
G01X32650Y525000D02*
X58551Y499099D01*
G01D02*
X63718D01*
G01D02*
X65634Y497183D01*
G01X73053Y492164D02*
X60982D01*
G01X69131Y511792D02*
X56468D01*
G01D02*
X40150Y528110D01*
G01X65811Y501970D02*
X57802D01*
G01D02*
X34150Y525622D01*
G01X69753Y510292D02*
X55846D01*
G01D02*
X38650Y527488D01*
G01X65119Y494480D02*
X62383Y497216D01*
G01D02*
X58312D01*
G01D02*
X31150Y524378D01*
G01X35650Y526244D02*
X58424Y503470D01*
G01D02*
X65123D01*
G01X70375Y508792D02*
X55224D01*
G01D02*
X37150Y526866D01*
G01X65283Y528239D02*
X60639D01*
G01D02*
X50000Y538878D01*
G01D02*
Y680900D01*
G01X32650Y658833D02*
Y525000D01*
G01X68509Y513292D02*
X57090D01*
G01D02*
X41750Y528632D01*
G01D02*
Y669550D01*
G01X40150Y528110D02*
Y670368D01*
G01X67000Y530400D02*
X60600D01*
G01D02*
X52600Y538400D01*
G01D02*
Y644600D01*
G01X45450Y680650D02*
Y541306D01*
G01D02*
X60656Y526100D01*
G01D02*
X65300D01*
G01X34150Y525622D02*
Y659455D01*
G01X60300Y533900D02*
X54100Y540100D01*
G01D02*
Y643483D01*
G01X38650Y527488D02*
Y669746D01*
G01X31150Y524378D02*
Y658211D01*
G01X61870Y515670D02*
X59288Y518252D01*
G01D02*
X54252D01*
G01D02*
X43500Y529004D01*
G01D02*
Y665600D01*
G01X35650Y660077D02*
Y526244D01*
G01X37150Y526866D02*
Y660699D01*
G01X52600Y644600D02*
X53000Y645000D01*
G01X54100Y643483D02*
X54850Y644233D01*
G01D02*
Y645767D01*
G01D02*
X54100Y646517D01*
G01D02*
Y666700D01*
G01X50000Y680900D02*
X45800Y685100D01*
G01X33600Y675800D02*
Y673700D01*
G01D02*
X31150Y671250D01*
G01D02*
Y660333D01*
G01D02*
X32650Y658833D01*
G01X41750Y669550D02*
X43100Y670900D01*
G01X40150Y670368D02*
X39900Y670618D01*
G01D02*
Y678100D01*
G01X42100Y684000D02*
X45450Y680650D01*
G01X34150Y659455D02*
X32650Y660955D01*
G01D02*
Y670062D01*
G01D02*
X35766Y673178D01*
G01X54100Y666700D02*
X54200Y666800D01*
G01X38650Y669746D02*
X38000Y670396D01*
G01D02*
Y684000D01*
G01X43500Y665600D02*
X43600Y665700D01*
G01X34500Y666500D02*
Y661227D01*
G01D02*
X35650Y660077D01*
G01X37150Y660699D02*
X36624Y661225D01*
G01D02*
Y669155D01*
G01X80877Y249110D02*
X108793Y221194D01*
G01X79377Y248488D02*
X103100Y224765D01*
G01X79400Y279728D02*
Y265822D01*
G01D02*
X80350Y264872D01*
G01D02*
Y257716D01*
G01D02*
X80877Y257189D01*
G01D02*
Y249110D01*
G01X77600Y280050D02*
Y274917D01*
G01D02*
X77650Y274867D01*
G01D02*
Y273333D01*
G01D02*
X77600Y273283D01*
G01D02*
Y265500D01*
G01D02*
X78850Y264250D01*
G01D02*
Y257094D01*
G01D02*
X79377Y256567D01*
G01D02*
Y248488D01*
G01X64583Y301500D02*
X70517D01*
G01D02*
X76767Y295250D01*
G01D02*
X78889D01*
G01D02*
X80850Y293289D01*
G01D02*
Y287900D01*
G01D02*
X81450Y287300D01*
G01D02*
Y281778D01*
G01D02*
X79400Y279728D01*
G01X64661Y299300D02*
X67483D01*
G01D02*
X71183Y295600D01*
G01D02*
X74295D01*
G01D02*
X76145Y293750D01*
G01D02*
X78267D01*
G01D02*
X79350Y292667D01*
G01D02*
Y287278D01*
G01D02*
X79950Y286678D01*
G01D02*
Y282400D01*
G01D02*
X77600Y280050D01*
G01X72651Y335151D02*
Y344809D01*
G01X82500Y357000D02*
X104522Y334978D01*
G01X82500Y362890D02*
Y357000D01*
G01X108382Y341000D02*
X97278Y352104D01*
G01D02*
Y370578D01*
G01D02*
X133154Y406454D01*
G01X99394Y391100D02*
X75384D01*
G01X72708Y382055D02*
X79153Y388500D01*
G01D02*
X100949D01*
G01X102593Y416333D02*
X89660Y403400D01*
G01D02*
X70985D01*
G01X100713Y405614D02*
X88599Y393500D01*
G01D02*
X63946D01*
G01X89500Y466600D02*
X86300Y469800D01*
G01D02*
Y473748D01*
G01D02*
X87598Y475046D01*
G01D02*
Y476580D01*
G01D02*
X86300Y477878D01*
G01D02*
Y478917D01*
G01D02*
X73053Y492164D01*
G01X65634Y497183D02*
X87037D01*
G01D02*
X110420Y473800D01*
G01X117246Y490122D02*
X92568Y514800D01*
G01X117331Y486973D02*
X92204Y512100D01*
G01D02*
X91003Y513300D01*
G01X70639D02*
X69131Y511792D01*
G01X112601Y476299D02*
X84550Y504350D01*
G01D02*
X68191D01*
G01D02*
X65811Y501970D01*
G01X118358Y483824D02*
X91357Y510825D01*
G01D02*
X90381Y511800D01*
G01D02*
X71261D01*
G01D02*
X69753Y510292D01*
G01X109900Y471500D02*
X88500Y492900D01*
G01D02*
X78245D01*
G01D02*
X76665Y494480D01*
G01D02*
X65119D01*
G01X65123Y503470D02*
X68154Y506501D01*
G01D02*
X71401D01*
G01D02*
X73218Y508318D01*
G01D02*
X87382D01*
G01D02*
X117300Y478400D01*
G01X117136Y482924D02*
X89759Y510300D01*
G01D02*
X71883D01*
G01D02*
X70375Y508792D01*
G01X119478Y497973D02*
X96951Y520500D01*
G01D02*
X90017D01*
G01D02*
X89967Y520550D01*
G01D02*
X88433D01*
G01D02*
X88383Y520500D01*
G01D02*
X76600D01*
G01D02*
X75289Y521811D01*
G01D02*
X71711D01*
G01D02*
X65283Y528239D01*
G01X92568Y514800D02*
X70017D01*
G01D02*
X68509Y513292D01*
G01X91003Y513300D02*
X70639D01*
G01X101145Y524800D02*
X72600D01*
G01D02*
X67000Y530400D01*
G01X65300Y526100D02*
X74700Y516700D01*
G01D02*
X95658D01*
G01D02*
X96759Y515600D01*
G01D02*
X117537Y494822D01*
G01X110160Y528620D02*
X88680Y550100D01*
G01X73900Y527050D02*
X71300Y529650D01*
G01D02*
Y537771D01*
G01D02*
X71420Y537891D01*
G01D02*
Y539425D01*
G01D02*
X71300Y539545D01*
G01D02*
Y541183D01*
G01D02*
X71850Y541733D01*
G01D02*
Y543267D01*
G01D02*
X70217Y544900D01*
G01D02*
X69200D01*
G01D02*
X65381Y548719D01*
G01X88680Y550100D02*
Y556613D01*
G01D02*
X87608Y557685D01*
G01X74500Y717200D02*
Y713400D01*
G01X94250Y803728D02*
Y738284D01*
G01D02*
X86966Y731000D01*
G01D02*
X85800D01*
G01X95900Y804600D02*
Y737600D01*
G01D02*
X85800Y727500D01*
G01X111300Y756000D02*
X97600Y742300D01*
G01Y736417D02*
X81283Y720100D01*
G01D02*
X77400D01*
G01D02*
X74500Y717200D01*
G01X91250Y816850D02*
Y806728D01*
G01D02*
X94250Y803728D01*
G01X93100Y813200D02*
Y807400D01*
G01D02*
X95900Y804600D01*
G01X93300Y818900D02*
X91250Y816850D01*
G01X111967Y213083D02*
Y199632D01*
G01X108793Y221194D02*
Y216257D01*
G01D02*
X111967Y213083D01*
G01X103100Y224765D02*
Y211600D01*
G01X97800Y285217D02*
Y272474D01*
G01D02*
X101463Y268811D01*
G01X104522Y276731D02*
X107340Y273913D01*
G01D02*
Y266140D01*
G01X99000Y334800D02*
Y286417D01*
G01D02*
X97800Y285217D01*
G01X104522Y334978D02*
Y276731D01*
G01X122000Y343300D02*
Y349198D01*
G01X100277Y336077D02*
X99000Y334800D01*
G01X133300Y320900D02*
X113195Y341000D01*
G01D02*
X108382D01*
G01X122000Y349198D02*
X144601Y371799D01*
G01X117300Y361700D02*
X122200D01*
G01D02*
X136240Y375740D01*
G01X102000Y364700D02*
X113150Y353550D01*
G01D02*
X124230D01*
G01D02*
X143979Y373299D01*
G01X131004Y422710D02*
X99394Y391100D01*
G01X100949Y388500D02*
X131304Y418855D01*
G01X120571Y416539D02*
X109646Y405614D01*
G01D02*
X100713D01*
G01X120200Y436400D02*
Y433940D01*
G01D02*
X109392Y423132D01*
G01D02*
Y420969D01*
G01D02*
X104756Y416333D01*
G01D02*
X102593D01*
G01X133154Y433726D02*
X127670Y439210D01*
G01D02*
Y449427D01*
G01X126122Y432323D02*
X120571Y426772D01*
G01D02*
Y416539D01*
G01X110420Y473800D02*
X122600D01*
G01X122700Y476100D02*
X122501Y476299D01*
G01D02*
X112601D01*
G01X122600Y471500D02*
X109900D01*
G01X127670Y449427D02*
X127820Y449577D01*
G01D02*
Y452280D01*
G01X117300Y478400D02*
X122700D01*
G01X121673Y497973D02*
X119478D01*
G01X132720Y490122D02*
X117246D01*
G01X127973Y488524D02*
X126422Y486973D01*
G01D02*
X117331D01*
G01X121673Y504272D02*
X101145Y524800D01*
G01X117537Y494822D02*
X121673D01*
G01X131122Y488524D02*
X129523Y486925D01*
G01D02*
Y484731D01*
G01D02*
X128616Y483824D01*
G01D02*
X118358D01*
G01X127973Y491674D02*
X127916D01*
G01D02*
X126421Y493169D01*
G01D02*
Y505179D01*
G01D02*
X125310Y506290D01*
G01D02*
X122130D01*
G01D02*
X110160Y518260D01*
G01X131122Y485374D02*
X130423Y484675D01*
G01D02*
Y484358D01*
G01D02*
X128989Y482924D01*
G01D02*
X117136D01*
G01X110160Y518260D02*
Y528620D01*
G01X97600Y742300D02*
Y736417D01*
G01X169709Y301732D02*
X163058D01*
G01D02*
X143890Y320900D01*
G01D02*
X133300D01*
G01X144601Y371799D02*
X156573D01*
G01X136240Y375740D02*
Y410313D01*
G01X143979Y373299D02*
Y376965D01*
G01D02*
X154883Y387869D01*
G01X136240Y410313D02*
X170750Y444823D01*
G01X154883Y387869D02*
X161210D01*
G01D02*
X171434Y398093D01*
G01X133154Y406454D02*
Y433726D01*
G01X134272Y491674D02*
X132720Y490122D01*
G01X139901Y548997D02*
X149981Y538917D01*
G01X170780Y554431D02*
X159449Y543100D01*
G01D02*
Y542048D01*
G01X165558Y547200D02*
X161067Y542709D01*
G01D02*
Y534774D01*
G01D02*
X160593Y534300D01*
G01D02*
X159923D01*
G01D02*
X159449Y534774D01*
G01D02*
Y538898D01*
G01X151644Y550690D02*
Y541294D01*
G01D02*
X153188Y539750D01*
G01D02*
Y538899D01*
G01X153194Y551294D02*
Y542078D01*
G01X166409Y540516D02*
X164217D01*
G01D02*
X162617Y538916D01*
G01X154744Y551014D02*
Y537379D01*
G01D02*
X153132Y535767D01*
G01X141401Y549690D02*
X151531Y539560D01*
G01D02*
Y537317D01*
G01D02*
X149985Y535771D01*
G01X136901Y547174D02*
X140209Y543866D01*
G01D02*
Y540269D01*
G01D02*
X144736Y535742D01*
G01D02*
X146858D01*
G01X157899Y550748D02*
Y528844D01*
G01D02*
X158824Y527919D01*
G01D02*
X168800D01*
G01X168900Y534000D02*
X164700D01*
G01D02*
X164300Y533600D01*
G01D02*
Y531400D01*
G01D02*
X163800Y530900D01*
G01D02*
X161198D01*
G01D02*
X159456Y532642D01*
G01X138401Y548274D02*
X142081Y544594D01*
G01D02*
Y541482D01*
G01D02*
X143043Y540520D01*
G01D02*
X145303D01*
G01D02*
X146869Y538954D01*
G01X167316Y538273D02*
X164809Y535766D01*
G01D02*
X162617D01*
G01X156300Y550900D02*
Y530408D01*
G01D02*
X153811Y527919D01*
G01D02*
X152525D01*
G01D02*
X151618Y528826D01*
G01D02*
Y531067D01*
G01D02*
X153187Y532636D01*
G01X144501Y548299D02*
X148900Y543900D01*
G01D02*
X149944D01*
G01D02*
X150744Y544700D01*
G01D02*
Y545985D01*
G01D02*
X150244Y546485D01*
G01D02*
X149400D01*
G01D02*
X148900Y546985D01*
G01X165675Y545124D02*
X162617Y542066D01*
G01X139901Y588601D02*
Y548997D01*
G01X146275Y580657D02*
Y564340D01*
G01D02*
X146775Y563840D01*
G01D02*
X148200D01*
G01D02*
X148700Y563340D01*
G01D02*
Y560000D01*
G01D02*
X148875Y559825D01*
G01D02*
Y559749D01*
G01D02*
X150439Y558185D01*
G01D02*
Y551895D01*
G01D02*
X151644Y550690D01*
G01X158530Y587099D02*
Y570269D01*
G01D02*
X155129Y566868D01*
G01D02*
Y553229D01*
G01D02*
X153194Y551294D01*
G01X160030Y587599D02*
Y569647D01*
G01D02*
X156629Y566246D01*
G01D02*
Y552899D01*
G01D02*
X154744Y551014D01*
G01X141401Y586331D02*
Y549690D01*
G01X134721Y581879D02*
X136901Y579699D01*
G01D02*
Y547174D01*
G01X163030Y591883D02*
Y560975D01*
G01D02*
X162005Y559950D01*
G01D02*
X160637D01*
G01D02*
X159730Y559043D01*
G01D02*
Y552579D01*
G01D02*
X157899Y550748D01*
G01X138401Y581722D02*
Y548274D01*
G01X167780Y558107D02*
X161029Y551356D01*
G01D02*
X160700D01*
G01X169280Y555480D02*
X162056Y548256D01*
G01D02*
X159537D01*
G01X161530Y588040D02*
Y569025D01*
G01D02*
X158166Y565661D01*
G01D02*
Y552766D01*
G01D02*
X156300Y550900D01*
G01X142951Y585251D02*
Y555636D01*
G01X144451Y584633D02*
Y562340D01*
G01D02*
X144951Y561840D01*
G01D02*
X146700D01*
G01D02*
X147200Y561340D01*
G01D02*
Y560340D01*
G01D02*
X146700Y559840D01*
G01D02*
X144951D01*
G01D02*
X144501Y559390D01*
G01D02*
Y558340D01*
G01D02*
X145001Y557840D01*
G01D02*
X145200D01*
G01D02*
X145700Y557340D01*
G01D02*
Y556340D01*
G01D02*
X145200Y555840D01*
G01D02*
X145001D01*
G01D02*
X144501Y555340D01*
G01D02*
Y554340D01*
G01D02*
X145001Y553840D01*
G01D02*
X145200D01*
G01D02*
X145700Y553340D01*
G01D02*
Y552340D01*
G01D02*
X145200Y551840D01*
G01D02*
X145001D01*
G01D02*
X144501Y551340D01*
G01D02*
Y548299D01*
G01X148900Y546985D02*
Y547985D01*
G01D02*
X149400Y548485D01*
G01D02*
X150244D01*
G01D02*
X150744Y548985D01*
G01D02*
Y550317D01*
G01D02*
X149539Y551522D01*
G01D02*
Y557500D01*
G01D02*
X149039Y558000D01*
G01D02*
X147951D01*
G01D02*
X147451Y557500D01*
G01D02*
Y556436D01*
G01X142418Y620300D02*
Y613452D01*
G01D02*
X142417Y613451D01*
G01D02*
Y610283D01*
G01D02*
X145567Y607133D01*
G01D02*
Y600901D01*
G01D02*
X144183Y599517D01*
G01D02*
Y594456D01*
G01D02*
X142418Y592691D01*
G01D02*
Y591118D01*
G01D02*
X139901Y588601D01*
G01X159716Y610945D02*
X161661Y609000D01*
G01D02*
X163700D01*
G01D02*
X170780Y601920D01*
G01X159716Y614095D02*
X161316Y612495D01*
G01D02*
X163508D01*
G01D02*
X164415Y611588D01*
G01D02*
Y610352D01*
G01D02*
X172280Y602487D01*
G01X150269Y598347D02*
X149618Y597696D01*
G01D02*
Y585918D01*
G01D02*
X148900Y585200D01*
G01D02*
X146918D01*
G01D02*
X146275Y584557D01*
G01D02*
Y583657D01*
G01D02*
X146775Y583157D01*
G01D02*
X152075D01*
G01D02*
X152575Y582657D01*
G01D02*
Y581657D01*
G01D02*
X152075Y581157D01*
G01D02*
X146775D01*
G01D02*
X146275Y580657D01*
G01X153417Y610945D02*
X155129Y609233D01*
G01D02*
Y590500D01*
G01D02*
X158530Y587099D01*
G01X151832Y615645D02*
Y613487D01*
G01D02*
X152824Y612495D01*
G01D02*
X157209D01*
G01D02*
X158116Y611588D01*
G01D02*
Y609584D01*
G01D02*
X158800Y608900D01*
G01D02*
X160200D01*
G01D02*
X160700Y608400D01*
G01D02*
Y606695D01*
G01D02*
X160200Y606195D01*
G01D02*
X157495D01*
G01D02*
X156629Y605329D01*
G01D02*
Y591000D01*
G01D02*
X160030Y587599D01*
G01X143968Y588898D02*
X141401Y586331D01*
G01X140821Y614106D02*
X139219Y612504D01*
G01D02*
X137035D01*
G01D02*
X136071Y611540D01*
G01D02*
Y609629D01*
G01D02*
X136500Y609200D01*
G01D02*
X141400D01*
G01D02*
X141900Y608700D01*
G01D02*
Y607000D01*
G01D02*
X141400Y606500D01*
G01D02*
X136671D01*
G01D02*
X136071Y605900D01*
G01D02*
Y594553D01*
G01D02*
X134721Y593203D01*
G01D02*
Y581879D01*
G01X159716Y595197D02*
X163030Y591883D01*
G01X143968Y601495D02*
Y604800D01*
G01D02*
X143468Y605300D01*
G01D02*
X139768D01*
G01D02*
X139268Y604800D01*
G01D02*
Y599897D01*
G01D02*
X139768Y599397D01*
G01D02*
X142000D01*
G01D02*
X142500Y598897D01*
G01D02*
Y597897D01*
G01D02*
X142000Y597397D01*
G01D02*
X139768D01*
G01D02*
X139268Y596897D01*
G01D02*
Y595897D01*
G01D02*
X139768Y595397D01*
G01D02*
X141000D01*
G01D02*
X141500Y594897D01*
G01D02*
Y593897D01*
G01D02*
X141000Y593397D01*
G01D02*
X136697D01*
G01D02*
X136000Y592700D01*
G01D02*
Y590722D01*
G01D02*
X136500Y590222D01*
G01D02*
X137901D01*
G01D02*
X138401Y589722D01*
G01D02*
Y588722D01*
G01D02*
X137901Y588222D01*
G01D02*
X136500D01*
G01D02*
X136000Y587722D01*
G01D02*
Y586722D01*
G01D02*
X136500Y586222D01*
G01D02*
X137901D01*
G01D02*
X138401Y585722D01*
G01D02*
Y584722D01*
G01D02*
X137901Y584222D01*
G01D02*
X136500D01*
G01D02*
X136000Y583722D01*
G01D02*
Y582722D01*
G01D02*
X136500Y582222D01*
G01D02*
X137901D01*
G01D02*
X138401Y581722D01*
G01X159716Y604645D02*
X158166Y603095D01*
G01D02*
Y591405D01*
G01D02*
X158635Y590935D01*
G01D02*
X161530Y588040D01*
G01X150268Y601496D02*
X148682Y599910D01*
G01D02*
X146472D01*
G01D02*
X145565Y599003D01*
G01D02*
Y587865D01*
G01D02*
X142951Y585251D01*
G01X147115Y598360D02*
X148133D01*
G01D02*
X148693Y597800D01*
G01D02*
Y593463D01*
G01D02*
X148193Y592963D01*
G01D02*
X147200D01*
G01D02*
X146700Y592463D01*
G01D02*
Y591463D01*
G01D02*
X147200Y590963D01*
G01D02*
X148193D01*
G01D02*
X148693Y590463D01*
G01D02*
Y588875D01*
G01D02*
X144451Y584633D01*
G01X147141Y614096D02*
Y620300D01*
G01D02*
X146641Y620800D01*
G01D02*
X142918D01*
G01D02*
X142418Y620300D01*
G01X162867Y614095D02*
X165058D01*
G01D02*
X175280Y603873D01*
G01X150251Y617226D02*
X151832Y615645D01*
G01X156566Y614095D02*
X158116Y615645D01*
G01D02*
X165630D01*
G01X162100Y677800D02*
X183650Y656250D01*
G01X164400Y668300D02*
X178942Y653758D01*
G01X195450Y662050D02*
X164500Y693000D01*
G01D02*
Y693500D01*
G01X167600Y247600D02*
Y253721D01*
G01D02*
X172550Y258671D01*
G01D02*
Y298891D01*
G01D02*
X169709Y301732D01*
G01X174943Y321015D02*
Y325336D01*
G01D02*
X179920Y330313D01*
G01D02*
Y354260D01*
G01D02*
X181800Y356140D01*
G01D02*
Y436059D01*
G01D02*
X195568Y449827D01*
G01X170750Y444823D02*
Y461051D01*
G01X195568Y449827D02*
Y461265D01*
G01D02*
X196239Y461936D01*
G01D02*
Y462262D01*
G01X177500Y454300D02*
Y461958D01*
G01D02*
X192457Y476915D01*
G01D02*
Y560142D01*
G01X170750Y461051D02*
X190957Y481258D01*
G01D02*
Y560764D01*
G01X189656Y558699D02*
Y541716D01*
G01D02*
X179008Y531068D01*
G01D02*
X173615D01*
G01D02*
X172065Y532618D01*
G01X175280Y548680D02*
X170216Y543616D01*
G01D02*
X168116D01*
G01D02*
X167316Y542816D01*
G01D02*
Y541423D01*
G01D02*
X166409Y540516D01*
G01X168800Y527919D02*
X169300Y528419D01*
G01D02*
Y533600D01*
G01D02*
X168900Y534000D01*
G01X175215Y532618D02*
X176765Y534168D01*
G01D02*
X178958D01*
G01D02*
X187650Y542860D01*
G01D02*
Y568606D01*
G01X176780Y547737D02*
X169509Y540466D01*
G01D02*
X168273D01*
G01D02*
X167316Y539509D01*
G01D02*
Y538273D01*
G01X178942Y653758D02*
Y543642D01*
G01D02*
X178365Y543065D01*
G01D02*
Y535768D01*
G01X173780Y549780D02*
X169124Y545124D01*
G01D02*
X165675D01*
G01X170780Y601920D02*
Y554431D01*
G01X172280Y602487D02*
Y550580D01*
G01D02*
X168900Y547200D01*
G01D02*
X165558D01*
G01X191151Y657093D02*
Y568666D01*
G01D02*
X191350Y568467D01*
G01D02*
Y566933D01*
G01D02*
X189456Y565039D01*
G01D02*
Y558899D01*
G01D02*
X189656Y558699D01*
G01X192457Y560142D02*
X194501Y562186D01*
G01D02*
Y571213D01*
G01D02*
X195450Y572162D01*
G01D02*
Y662050D01*
G01X185500Y567700D02*
Y568578D01*
G01D02*
X187871Y570949D01*
G01D02*
Y656129D01*
G01X175280Y603873D02*
Y548680D01*
G01X187650Y568606D02*
X189371Y570327D01*
G01D02*
Y656751D01*
G01X190957Y560764D02*
X193001Y562808D01*
G01D02*
Y574708D01*
G01X183650Y656250D02*
Y566933D01*
G01D02*
X184189Y566394D01*
G01D02*
Y564504D01*
G01X167780Y596580D02*
Y558107D01*
G01X169280Y598232D02*
Y555480D01*
G01X176780Y604495D02*
Y547737D01*
G01X173780Y603180D02*
Y549780D01*
G01X166015Y598345D02*
X167780Y596580D01*
G01X166016Y601496D02*
X169280Y598232D01*
G01X165630Y615645D02*
X176780Y604495D01*
G01X166016Y610944D02*
X173780Y603180D01*
G01X189000Y684500D02*
X195000Y678500D01*
G01D02*
X199500D01*
G01X175200D02*
X174300Y677600D01*
G01D02*
Y673944D01*
G01D02*
X191151Y657093D01*
G01X187871Y656129D02*
X167000Y677000D01*
G01D02*
Y686500D01*
G01X204570Y662430D02*
X185000Y682000D01*
G01X189371Y656751D02*
X172300Y673822D01*
G01D02*
Y677300D01*
G01D02*
X171300Y678300D01*
G01X185000Y682000D02*
Y684500D01*
G01X262002Y107146D02*
X227904D01*
G01D02*
X227273Y106515D01*
G01D02*
X224537D01*
G01D02*
X221418Y109634D01*
G01X224576Y116678D02*
X226478Y118580D01*
G01D02*
X259331D01*
G01X233500Y137000D02*
X227730Y131230D01*
G01D02*
X226280D01*
G01D02*
X225650Y130600D01*
G01D02*
X221600D01*
G01D02*
X220300Y129300D01*
G01X222140Y315643D02*
Y300560D01*
G01D02*
X222200Y300500D01*
G01X215400Y346941D02*
Y322382D01*
G01D02*
X222140Y315643D01*
G01X227100Y402100D02*
Y365600D01*
G01D02*
X228100Y364600D01*
G01X212536Y349805D02*
X215400Y346941D01*
G01X206776Y422424D02*
X227100Y402100D01*
G01X205915Y422424D02*
X206776D01*
G01X232717Y446800D02*
X228900D01*
G01X205450Y546650D02*
X203300Y544500D01*
G01X210592Y653032D02*
Y556270D01*
G01D02*
X210466Y556144D01*
G01D02*
Y549649D01*
G01D02*
X207467Y546650D01*
G01D02*
X205450D01*
G01X206700Y554500D02*
X209092Y556892D01*
G01D02*
Y653031D01*
G01X205700Y559763D02*
Y651386D01*
G01X225249Y583602D02*
X234783Y574068D01*
G01X207592Y652409D02*
Y558792D01*
G01D02*
X203447Y554647D01*
G01D02*
Y554684D01*
G01D02*
X203304D01*
G01X225249Y675025D02*
Y583602D01*
G01X199500Y678500D02*
X210466Y667534D01*
G01D02*
Y666056D01*
G01D02*
X210592Y665930D01*
G01D02*
Y657368D01*
G01D02*
X210591Y656125D01*
G01D02*
Y654275D01*
G01D02*
X210592Y653032D01*
G01X209092Y653031D02*
X209091Y654274D01*
G01D02*
Y656126D01*
G01D02*
X209092Y657369D01*
G01D02*
Y665308D01*
G01D02*
X201000Y673400D01*
G01D02*
Y674000D01*
G01X205700Y651386D02*
X204570Y652516D01*
G01D02*
Y662430D01*
G01X219000Y694000D02*
Y681395D01*
G01D02*
X225010Y675385D01*
G01D02*
Y675264D01*
G01D02*
X225249Y675025D01*
G01X206952Y655370D02*
X207091D01*
G01D02*
X207591Y654871D01*
G01D02*
Y652410D01*
G01D02*
X207592Y652409D01*
G01X244500Y686000D02*
X231500Y699000D01*
G01X264443Y109587D02*
X262002Y107146D01*
G01X273400Y302246D02*
X265450Y310196D01*
G01D02*
Y360350D01*
G01X245400Y296500D02*
X244762D01*
G01D02*
X238400Y302862D01*
G01D02*
Y387450D01*
G01X296154Y259030D02*
X251010Y304174D01*
G01D02*
Y371539D01*
G01X265450Y360350D02*
X267300Y362200D01*
G01X251010Y371539D02*
X253550Y374079D01*
G01D02*
Y425967D01*
G01X239100Y415114D02*
Y399200D01*
G01X238400Y387450D02*
X239100Y388150D01*
G01D02*
Y399200D01*
G01X238400Y416200D02*
Y415814D01*
G01D02*
X239100Y415114D01*
G01X253550Y425967D02*
X232717Y446800D01*
G01X276150Y522622D02*
X250388Y548384D01*
G01D02*
Y575710D01*
G01D02*
X244500Y581598D01*
G01X234783Y574068D02*
Y572921D01*
G01D02*
X234777Y556282D01*
G01D02*
Y550569D01*
G01X244500Y581598D02*
Y686000D01*
G01X270100Y652200D02*
X256600D01*
G01X281375Y711500D02*
X251000D01*
G01D02*
X241000Y721500D01*
G01X289796Y708000D02*
X245500D01*
G01D02*
X241000Y712500D01*
G01Y725500D02*
X253000Y713500D01*
G01D02*
X279500D01*
G01X284844Y709500D02*
X249500D01*
G01D02*
X241000Y718000D01*
G01X301600Y271500D02*
X274900Y298200D01*
G01X300500Y270000D02*
X273400Y297100D01*
G01X379636Y259030D02*
X296154D01*
G01X274900Y298200D02*
Y302868D01*
G01D02*
X271699Y306069D01*
G01D02*
Y309181D01*
G01D02*
X267420Y313460D01*
G01X293550Y353450D02*
Y309556D01*
G01D02*
X305880Y297226D01*
G01X273400Y297100D02*
Y302246D01*
G01X267420Y313460D02*
Y326143D01*
G01D02*
X269150Y327873D01*
G01D02*
Y341329D01*
G01D02*
X267979Y342500D01*
G01X295400Y325390D02*
Y351735D01*
G01X287200Y359935D02*
Y326802D01*
G01X306570Y367929D02*
X299103Y375396D01*
G01D02*
Y377618D01*
G01D02*
X299102Y377620D01*
G01D02*
Y454625D01*
G01X295400Y351735D02*
X303170Y359505D01*
G01Y367085D02*
X295999Y374256D01*
G01D02*
Y486923D01*
G01X301320Y361220D02*
X293550Y353450D01*
G01X288270Y365240D02*
X290100Y367070D01*
G01D02*
Y488578D01*
G01X297602Y411467D02*
Y374775D01*
G01D02*
X305070Y367307D01*
G01X291600Y489422D02*
Y364335D01*
G01D02*
X287200Y359935D01*
G01X297500Y411569D02*
X297602Y411467D01*
G01X297500Y487544D02*
Y411569D01*
G01X299102Y454625D02*
X299200Y454723D01*
G01D02*
Y487966D01*
G01D02*
X296722Y490444D01*
G01D02*
Y503100D01*
G01D02*
X291900Y507922D01*
G01D02*
Y519323D01*
G01X295999Y486923D02*
X293721Y489201D01*
G01D02*
Y489423D01*
G01D02*
X288400Y494744D01*
G01D02*
Y504336D01*
G01D02*
X283603Y509133D01*
G01D02*
Y513509D01*
G01X290100Y488578D02*
X282682Y495996D01*
G01D02*
Y505810D01*
G01D02*
X276150Y512342D01*
G01D02*
Y522622D01*
G01X288030Y517670D02*
Y510792D01*
G01D02*
X288029Y510791D01*
G01D02*
Y509549D01*
G01D02*
X293440Y504138D01*
G01D02*
X293562D01*
G01D02*
X295221Y502479D01*
G01D02*
Y489823D01*
G01D02*
X297500Y487544D01*
G01X278350Y553150D02*
Y512264D01*
G01D02*
X284182Y506432D01*
G01D02*
Y496840D01*
G01D02*
X291600Y489422D01*
G01X291900Y519323D02*
X291896Y519424D01*
G01D02*
X291900Y519448D01*
G01D02*
Y557100D01*
G01X283603Y513509D02*
X280200Y516912D01*
G01D02*
Y551400D01*
G01X283600D02*
Y522100D01*
G01D02*
X288030Y517670D01*
G01X291900Y557100D02*
X296200Y561400D01*
G01D02*
Y566900D01*
G01X279994Y554794D02*
X278350Y553150D01*
G01X536535Y372265D02*
X275050Y633750D01*
G01D02*
Y647250D01*
G01D02*
X270100Y652200D01*
G01X286406Y716531D02*
X281375Y711500D01*
G01X307278Y725482D02*
X289796Y708000D01*
G01X279500Y713500D02*
X282406Y716406D01*
G01X290338Y715800D02*
Y714994D01*
G01D02*
X284844Y709500D01*
G01X282406Y716406D02*
Y716598D01*
G01X381200Y271500D02*
X301600D01*
G01X380500Y270000D02*
X300500D01*
G01X302500Y251600D02*
X305810Y248290D01*
G01D02*
X383130D01*
G01X305880Y297226D02*
Y291420D01*
G01D02*
X306800Y290500D01*
G01X303517Y330317D02*
Y309777D01*
G01X311882Y310550D02*
X306570Y315862D01*
G01D02*
Y367929D01*
G01X305070Y367307D02*
Y331870D01*
G01D02*
X303517Y330317D01*
G01X303170Y359505D02*
Y367085D01*
G01X301320Y362500D02*
Y361220D01*
G01X307278Y726198D02*
Y725482D01*
G01X349970Y256720D02*
X379824D01*
G01X345820Y256570D02*
X347770Y254620D01*
G01D02*
X378922D01*
G01X404915Y184585D02*
X400400Y189100D01*
G01X379824Y256720D02*
X446500Y190044D01*
G01X378922Y254620D02*
X445000Y188542D01*
G01X383130Y248290D02*
X431027Y200393D01*
G01X448000Y190666D02*
X379636Y259030D01*
G01X439250Y213450D02*
X381200Y271500D01*
G01X444100Y206400D02*
X380500Y270000D01*
G01X501145Y5629D02*
X428809Y77965D01*
G01X419267Y75483D02*
X506185Y-11435D01*
G01X504112Y-16435D02*
X413068Y74609D01*
G01X428809Y77965D02*
Y154260D01*
G01X419267Y151778D02*
Y75483D01*
G01X413068Y74609D02*
Y150626D01*
G01X428809Y154260D02*
X421757Y161312D01*
G01D02*
Y177999D01*
G01X412159Y183141D02*
Y158886D01*
G01D02*
X419267Y151778D01*
G01X413068Y150626D02*
X404915Y158779D01*
G01D02*
Y184585D01*
G01X431027Y200393D02*
Y170577D01*
G01D02*
X431028Y170576D01*
G01D02*
Y164065D01*
G01D02*
X438000Y157093D01*
G01X433000Y169700D02*
Y164215D01*
G01D02*
X439500Y157715D01*
G01X411400Y183900D02*
X412159Y183141D01*
G01X437999Y84855D02*
X460050Y62804D01*
G01D02*
Y61533D01*
G01D02*
X461133Y60450D01*
G01D02*
X462404D01*
G01D02*
X465127Y57727D01*
G01X447000Y110933D02*
X496350Y61583D01*
G01X445500Y110304D02*
X494850Y60952D01*
G01X437999Y109921D02*
Y84855D01*
G01X439499Y109299D02*
Y107643D01*
G01D02*
X488850Y58292D01*
G01X497850Y62304D02*
X448500Y111654D01*
G01X447000Y160824D02*
Y110933D01*
G01X445500Y160202D02*
Y110304D01*
G01X438000Y157093D02*
X437999Y109921D01*
G01X439500Y157715D02*
Y109300D01*
G01D02*
X439499Y109299D01*
G01X448500Y111654D02*
Y161446D01*
G01X446500Y190044D02*
Y161324D01*
G01D02*
X447000Y160824D01*
G01X445000Y188542D02*
Y160702D01*
G01D02*
X445500Y160202D01*
G01X448500Y161446D02*
X448000Y161946D01*
G01D02*
Y190666D01*
G01X472823Y206400D02*
X444100D01*
G01X489353Y213450D02*
X439250D01*
G01X517813Y5629D02*
X501145D01*
G01X488850Y46616D02*
X524551Y10915D01*
G01X529300Y21415D02*
X499350Y51365D01*
G01D02*
Y63915D01*
G01D02*
X485116Y78149D01*
G01X496350Y61583D02*
Y49725D01*
G01D02*
X527660Y18415D01*
G01X494850Y60952D02*
Y49103D01*
G01D02*
X527038Y16915D01*
G01X486616Y78771D02*
X500850Y64537D01*
G01D02*
Y51987D01*
G01D02*
X529922Y22915D01*
G01X489616Y80015D02*
X503850Y65781D01*
G01X530544Y24415D02*
X502350Y52609D01*
G01D02*
Y65159D01*
G01D02*
X488116Y79393D01*
G01X488850Y58292D02*
Y46616D01*
G01X528282Y19915D02*
X497850Y50347D01*
G01D02*
Y62304D01*
G01X485116Y78149D02*
Y138416D01*
G01X486616Y135819D02*
Y78771D01*
G01X489616Y134575D02*
Y80015D01*
G01X488116Y79393D02*
Y135197D01*
G01X510985Y151700D02*
X494693Y135408D01*
G01D02*
Y129406D01*
G01D02*
X502999Y121100D01*
G01X485116Y138416D02*
X502125Y155425D01*
G01X507300Y156504D02*
X486616Y135819D01*
G01X510841Y155800D02*
X489616Y134575D01*
G01X488116Y135197D02*
X511319Y158400D01*
G01X505350Y115416D02*
X493193Y127573D01*
G01D02*
Y136030D01*
G01D02*
X511263Y154100D01*
G01X502125Y155425D02*
Y173139D01*
G01D02*
X506336Y177350D01*
G01X565141Y208560D02*
X494243D01*
G01D02*
X489353Y213450D01*
G01X488462Y190761D02*
X472823Y206400D01*
G01X710770Y2415D02*
X521027D01*
G01D02*
X517813Y5629D01*
G01X506185Y-11435D02*
X964940D01*
G01X967252Y-16435D02*
X504112D01*
G01X684333Y21415D02*
X529300D01*
G01X527660Y18415D02*
X685577D01*
G01X527038Y16915D02*
X686199D01*
G01X529922Y22915D02*
X683711D01*
G01X503850Y53231D02*
X531166Y25915D01*
G01D02*
X682467D01*
G01X683089Y24415D02*
X530544D01*
G01X681845Y27415D02*
X531788D01*
G01D02*
X505350Y53853D01*
G01X524551Y10915D02*
X697565D01*
G01X684955Y19915D02*
X528282D01*
G01X503850Y65781D02*
Y53231D01*
G01X505350Y53853D02*
Y115416D01*
G01X502999Y121100D02*
X668356D01*
G01X529176Y151713D02*
X529163Y151700D01*
G01D02*
X510985D01*
G01X507300Y175500D02*
Y156504D01*
G01X535960Y151999D02*
X532159Y155800D01*
G01D02*
X510841D01*
G01X511319Y158400D02*
X542181D01*
G01X511263Y154100D02*
X530506D01*
G01D02*
X532560Y152046D01*
G01X506336Y177350D02*
X548020D01*
G01X549100Y126900D02*
X556700D01*
G01D02*
X559069Y129269D01*
G01D02*
X559297D01*
G01D02*
X559866Y129838D01*
G01D02*
X561400D01*
G01D02*
X561969Y129269D01*
G01D02*
X609131D01*
G01X548020Y177350D02*
X558121Y167249D01*
G01X542181Y158400D02*
X545054Y161273D01*
G01D02*
X547240D01*
G01D02*
X549437Y163470D01*
G01D02*
X557162D01*
G01D02*
X561627Y167935D01*
G01D02*
X564483D01*
G01X574459Y199242D02*
X565141Y208560D01*
G01X561300Y369500D02*
X558535Y372265D01*
G01D02*
X536535D01*
G01X626203Y199242D02*
X574459D01*
G01X596253Y210000D02*
X599373Y206880D01*
G01D02*
X611635D01*
G01X576100Y234500D02*
X576650Y233950D01*
G01D02*
X577906D01*
G01D02*
X578256Y233600D01*
G01D02*
X580154D01*
G01D02*
X588196Y225558D01*
G01D02*
X592430D01*
G01D02*
X596122Y229250D01*
G01D02*
X605546D01*
G01X609131Y129269D02*
X614800Y123600D01*
G01D02*
X667978D01*
G01X614721Y138287D02*
X614924Y138490D01*
G01D02*
Y142524D01*
G01D02*
X616900Y144500D01*
G01D02*
X617000D01*
G01X635482Y207733D02*
X634694D01*
G01D02*
X626203Y199242D01*
G01X611635Y206880D02*
X618869Y214114D01*
G01X605546Y229250D02*
X605548Y229252D01*
G01D02*
X611205D01*
G01D02*
X616970Y235017D01*
G01X618869Y214114D02*
X643354D01*
G01X668356Y121100D02*
X702936Y86520D01*
G01X667978Y123600D02*
X704436Y87142D01*
G01X643354Y214114D02*
X649081Y208387D01*
G01D02*
Y202026D01*
G01D02*
X652342Y198765D01*
G01D02*
X671552D01*
G01X706915Y43997D02*
X684333Y21415D01*
G01X685577Y18415D02*
X708909Y41747D01*
G01X686199Y16915D02*
X686288Y17004D01*
G01D02*
X686294D01*
G01D02*
X709507Y40217D01*
G01X683711Y22915D02*
X705415Y44619D01*
G01X682467Y25915D02*
X702415Y45863D01*
G01X703915Y45241D02*
X683089Y24415D01*
G01X700914Y46484D02*
X681845Y27415D01*
G01X697565Y10915D02*
X705050Y18400D01*
G01X708415Y43375D02*
X684955Y19915D01*
G01X702415Y45863D02*
Y47105D01*
G01D02*
X702414Y47106D01*
G01D02*
Y54272D01*
G01D02*
X711419Y63277D01*
G01X712041Y61777D02*
X703914Y53650D01*
G01D02*
Y47728D01*
G01D02*
X703915Y47727D01*
G01D02*
Y45241D01*
G01X710797Y64777D02*
X700914Y54894D01*
G01D02*
Y46484D01*
G01X702936Y86520D02*
Y81097D01*
G01D02*
X712534Y71499D01*
G01X704436Y87142D02*
Y81719D01*
G01D02*
X713155Y73000D01*
G01X671552Y198765D02*
X691150Y179167D01*
G01D02*
X700625D01*
G01D02*
X702296Y180838D01*
G01D02*
X759389D01*
G01X772650Y4250D02*
X737600D01*
G01D02*
X734150Y7700D01*
G01X716055D02*
X710770Y2415D01*
G01X734150Y7700D02*
X716055D01*
G01X709507Y40217D02*
X714224D01*
G01D02*
X714226Y40219D01*
G01D02*
X715882D01*
G01D02*
X715883Y40218D01*
G01D02*
X717539D01*
G01D02*
X717540Y40217D01*
G01D02*
X735050D01*
G01D02*
X744733Y49900D01*
G01X721890Y24887D02*
Y22883D01*
G01D02*
X723323Y21450D01*
G01D02*
X731182D01*
G01D02*
X740949Y31217D01*
G01X729000Y24800D02*
X738417Y34217D01*
G01D02*
X828198D01*
G01X740327Y32717D02*
X730560Y22950D01*
G01D02*
X727115D01*
G01D02*
X725314Y24751D01*
G01X741571Y29717D02*
X731804Y19950D01*
G01D02*
X721057D01*
G01D02*
X719008Y21999D01*
G01X705050Y18400D02*
X735489D01*
G01D02*
X743490Y26401D01*
G01X712534Y71499D02*
X713776D01*
G01D02*
X713777Y71500D01*
G01D02*
X748583D01*
G01X753455Y58777D02*
X713285D01*
G01D02*
X706914Y52406D01*
G01D02*
Y48972D01*
G01D02*
X706915Y48971D01*
G01D02*
Y43997D01*
G01X708909Y41747D02*
X717365D01*
G01D02*
X722457Y46839D01*
G01D02*
Y50997D01*
G01D02*
X727214Y55754D01*
G01D02*
X756472D01*
G01X705415Y44619D02*
Y48349D01*
G01D02*
X705414Y48350D01*
G01D02*
Y53028D01*
G01D02*
X712663Y60277D01*
G01D02*
X752833D01*
G01X711419Y63277D02*
X744605D01*
G01X745950Y61777D02*
X712041D01*
G01X743983Y64777D02*
X710797D01*
G01X713155Y73000D02*
X744622D01*
G01X754076Y57276D02*
X713906D01*
G01D02*
X708414Y51784D01*
G01D02*
Y49594D01*
G01D02*
X708415Y49593D01*
G01D02*
Y43375D01*
G01X740949Y31217D02*
X773983D01*
G01X828547Y32717D02*
X740327D01*
G01X773361Y29717D02*
X741571D01*
G01X743490Y26401D02*
X774399D01*
G01X748583Y71500D02*
X752184Y75100D01*
G01X768929Y74251D02*
X753455Y58777D01*
G01X756472Y55754D02*
X771212Y70494D01*
G01D02*
X789541D01*
G01X744733Y49900D02*
X753550D01*
G01D02*
X772644Y68994D01*
G01X752833Y60277D02*
X768306Y75750D01*
G01X744605Y63277D02*
X753428Y72100D01*
G01D02*
X760412D01*
G01D02*
X767062Y78750D01*
G01X767684Y77250D02*
X760878Y70444D01*
G01D02*
X754617D01*
G01D02*
X745950Y61777D01*
G01X766440Y80250D02*
X759790Y73600D01*
G01D02*
X752806D01*
G01D02*
X743983Y64777D01*
G01X744622Y73000D02*
X748822Y77200D01*
G01X790133Y72750D02*
X769550D01*
G01D02*
X754076Y57276D01*
G01X752184Y75100D02*
X758189D01*
G01D02*
X764839Y81750D01*
G01D02*
X767864D01*
G01D02*
X767874Y81752D01*
G01D02*
X772038D01*
G01D02*
X772039Y81751D01*
G01D02*
X773281D01*
G01X785999Y74250D02*
X770172D01*
G01D02*
X768929Y74251D01*
G01X768306Y75750D02*
X768460D01*
G01D02*
X768470Y75752D01*
G01D02*
X769550D01*
G01D02*
X769551Y75751D01*
G01D02*
X770793D01*
G01D02*
X770794Y75750D01*
G01D02*
X785377D01*
G01X767062Y78750D02*
X768162D01*
G01D02*
X768172Y78752D01*
G01D02*
X770794D01*
G01D02*
X770795Y78751D01*
G01D02*
X772037D01*
G01D02*
X772038Y78750D01*
G01D02*
X784133D01*
G01X784755Y77250D02*
X771416D01*
G01D02*
X771415Y77251D01*
G01D02*
X770173D01*
G01D02*
X770172Y77252D01*
G01D02*
X768321D01*
G01D02*
X768311Y77250D01*
G01D02*
X767684D01*
G01X772659Y80251D02*
X771417D01*
G01D02*
X771416Y80252D01*
G01D02*
X768023D01*
G01D02*
X768013Y80250D01*
G01D02*
X766440D01*
G01X748822Y77200D02*
X757600D01*
G01D02*
X759600Y79200D01*
G01X759389Y180838D02*
X768777Y171450D01*
G01X815166Y-2836D02*
X803830Y8500D01*
G01X776900D02*
X772650Y4250D01*
G01X803830Y8500D02*
X776900D01*
G01X773983Y31217D02*
X778150Y27050D01*
G01D02*
X805249D01*
G01D02*
X807319Y29120D01*
G01X807941Y27620D02*
X805871Y25550D01*
G01D02*
X778772D01*
G01D02*
X778771Y25549D01*
G01D02*
X777529D01*
G01D02*
X773361Y29717D01*
G01X774399Y26401D02*
X777400Y23400D01*
G01D02*
X816950D01*
G01X846399Y71150D02*
X799218D01*
G01D02*
X794318Y76050D01*
G01X787799D02*
X785999Y74250D01*
G01X789541Y70494D02*
X795635Y64400D01*
G01D02*
X908556D01*
G01X772644Y68994D02*
X788919D01*
G01D02*
X795013Y62900D01*
G01D02*
X909178D01*
G01X794940Y77550D02*
X799840Y72650D01*
G01D02*
X845777D01*
G01X782551Y67144D02*
X790995Y58700D01*
G01D02*
X900972D01*
G01X831378Y54700D02*
X786796D01*
G01D02*
X775381Y66115D01*
G01X845155Y74150D02*
X800462D01*
G01D02*
X795562Y79050D01*
G01X778800Y66388D02*
X788988Y56200D01*
G01D02*
X865923D01*
G01X903834Y61000D02*
X792296D01*
G01D02*
X786333Y66963D01*
G01X806730Y66250D02*
X796633D01*
G01D02*
X790133Y72750D01*
G01X773281Y81751D02*
X773282Y81750D01*
G01D02*
X782889D01*
G01D02*
X784689Y83550D01*
G01D02*
X804150D01*
G01D02*
X806750Y80950D01*
G01X794318Y76050D02*
X787799D01*
G01X785377Y75750D02*
X787177Y77550D01*
G01D02*
X794940D01*
G01X784133Y78750D02*
X785933Y80550D01*
G01D02*
X801572D01*
G01D02*
X804172Y77950D01*
G01D02*
X819289D01*
G01X795562Y79050D02*
X786555D01*
G01D02*
X784755Y77250D01*
G01X819911Y79450D02*
X805250D01*
G01D02*
X802650Y82050D01*
G01D02*
X785311D01*
G01D02*
X783511Y80250D01*
G01D02*
X772660D01*
G01D02*
X772659Y80251D01*
G01X960628Y-2836D02*
X815166D01*
G01X830500Y20800D02*
X830700D01*
G01D02*
X834050Y17450D01*
G01D02*
X862750D01*
G01X807319Y29120D02*
X833332D01*
G01D02*
X841652Y20800D01*
G01X828198Y34217D02*
X830242Y36261D01*
G01D02*
X833698D01*
G01D02*
X849051Y20908D01*
G01X845052Y20800D02*
X834792Y31061D01*
G01D02*
X830203D01*
G01D02*
X828547Y32717D01*
G01X878540Y14450D02*
X831650D01*
G01D02*
X824462Y21638D01*
G01D02*
Y25770D01*
G01X838252Y20800D02*
X831432Y27620D01*
G01D02*
X807941D01*
G01X816950Y23400D02*
X821110Y19240D01*
G01D02*
X824738D01*
G01D02*
X831028Y12950D01*
G01D02*
X877918D01*
G01X862050Y18950D02*
X836350D01*
G01D02*
X834500Y20800D01*
G01X828283Y24734D02*
Y20303D01*
G01D02*
X832636Y15950D01*
G01D02*
X879162D01*
G01X852228Y33850D02*
X831378Y54700D01*
G01X808114Y67634D02*
X806730Y66250D01*
G01X806750Y80950D02*
X820533D01*
G01D02*
X822782Y78701D01*
G01D02*
X843340D01*
G01X823551Y80551D02*
X825968Y82968D01*
G01D02*
X868032D01*
G01X819289Y77950D02*
X821538Y75701D01*
G01D02*
X844584D01*
G01X843962Y77201D02*
X822160D01*
G01D02*
X819911Y79450D01*
G01X862750Y17450D02*
X866065Y20765D01*
G01D02*
X875235D01*
G01X909804Y33850D02*
X852228D01*
G01X875857Y22265D02*
X865365D01*
G01D02*
X862050Y18950D01*
G01X902436Y71914D02*
X861878D01*
G01D02*
X861328Y72464D01*
G01D02*
X853894D01*
G01D02*
X852019Y70589D01*
G01X900731Y73414D02*
X863646D01*
G01D02*
X863096Y73964D01*
G01D02*
X849213D01*
G01D02*
X846399Y71150D01*
G01X907053Y68764D02*
X857208D01*
G01D02*
X855421Y70551D01*
G01X845777Y72650D02*
X848591Y75464D01*
G01X847969Y76964D02*
X845155Y74150D01*
G01X865923Y56200D02*
X877123Y45000D01*
G01X848623Y70757D02*
X849026D01*
G01D02*
X852519Y67264D01*
G01D02*
X908264D01*
G01X906581Y70414D02*
X859021D01*
G01D02*
X858821Y70614D01*
G01X843340Y78701D02*
X846103Y81464D01*
G01D02*
X867414D01*
G01D02*
X867964Y80914D01*
G01D02*
X891131D01*
G01X868032Y82968D02*
X868586Y82414D01*
G01D02*
X887931D01*
G01X848591Y75464D02*
X864926D01*
G01D02*
X865476Y74914D01*
G01D02*
X897732D01*
G01X844584Y75701D02*
X847347Y78464D01*
G01D02*
X866170D01*
G01D02*
X866720Y77914D01*
G01D02*
X896488D01*
G01X897110Y76414D02*
X866098D01*
G01D02*
X865548Y76964D01*
G01D02*
X847969D01*
G01X894131Y79414D02*
X867342D01*
G01D02*
X866792Y79964D01*
G01D02*
X846725D01*
G01D02*
X843962Y77201D01*
G01X880797Y83914D02*
X870186D01*
G01D02*
X868800Y85300D01*
G01X875235Y20765D02*
X875750Y20250D01*
G01D02*
X880096D01*
G01D02*
X880097Y20249D01*
G01D02*
X881339D01*
G01D02*
X886890Y25800D01*
G01D02*
X952965D01*
G01X900776Y45000D02*
X910869Y34907D01*
G01X954209Y22800D02*
X888134D01*
G01D02*
X879783Y14449D01*
G01D02*
X878541D01*
G01D02*
X878540Y14450D01*
G01X877918Y12950D02*
X877919Y12949D01*
G01D02*
X880405D01*
G01D02*
X880406Y12950D01*
G01D02*
X882267D01*
G01D02*
X889845Y20528D01*
G01D02*
X958511D01*
G01X952343Y27300D02*
X886268D01*
G01D02*
X880718Y21750D01*
G01D02*
X876372D01*
G01D02*
X875857Y22265D01*
G01X879162Y15950D02*
X887512Y24300D01*
G01D02*
X953587D01*
G01X919600Y89078D02*
X902436Y71914D01*
G01X911850Y84533D02*
X900731Y73414D01*
G01X922600Y84311D02*
X907053Y68764D01*
G01X900972Y58700D02*
X905193Y54479D01*
G01D02*
X905488D01*
G01X877123Y45000D02*
X900776D01*
G01X909797Y55037D02*
X903834Y61000D01*
G01X921100Y84933D02*
X906581Y70414D01*
G01X891131Y80914D02*
X894850Y84633D01*
G01D02*
Y86011D01*
G01D02*
X912243Y103404D01*
G01X887931Y82414D02*
X891050Y85533D01*
G01D02*
Y86067D01*
G01D02*
X892133Y87150D01*
G01D02*
X892189D01*
G01D02*
X911000Y105961D01*
G01X897732Y74914D02*
X907908Y85090D01*
G01X896488Y77914D02*
X903850Y85276D01*
G01D02*
Y90514D01*
G01D02*
X914750Y101414D01*
G01X916250Y99865D02*
X906408Y90023D01*
G01D02*
Y85712D01*
G01D02*
X897110Y76414D01*
G01X914900Y103686D02*
X899450Y88236D01*
G01D02*
Y84733D01*
G01D02*
X894131Y79414D01*
G01X908243Y107243D02*
X898850Y97850D01*
G01D02*
Y95933D01*
G01D02*
X896917Y94000D01*
G01D02*
X894911D01*
G01D02*
X888888Y87977D01*
G01D02*
X887960D01*
G01D02*
X887333Y87350D01*
G01D02*
X884233D01*
G01D02*
X880797Y83914D01*
G01X922772Y53139D02*
Y39395D01*
G01D02*
X916784Y33407D01*
G01D02*
X910247D01*
G01D02*
X909804Y33850D01*
G01X910869Y34907D02*
X916162D01*
G01D02*
X921272Y40017D01*
G01D02*
Y58854D01*
G01X908556Y64400D02*
X913006Y68850D01*
G01D02*
X937850D01*
G01D02*
X948200Y79200D01*
G01X909178Y62900D02*
X913628Y67350D01*
G01D02*
X938472D01*
G01D02*
X948822Y77700D01*
G01X958100Y60245D02*
X929878D01*
G01D02*
X922772Y53139D01*
G01X921272Y58854D02*
X924768Y62350D01*
G01D02*
X958655D01*
G01X908264Y67264D02*
X924100Y83100D01*
G01X912243Y103404D02*
Y113500D01*
G01X922000Y109800D02*
Y103472D01*
G01D02*
X920750Y102222D01*
G01D02*
Y97999D01*
G01D02*
X919600Y96849D01*
G01D02*
Y89078D01*
G01X920400Y112400D02*
Y103372D01*
G01D02*
X919250Y102222D01*
G01D02*
Y98621D01*
G01D02*
X911850Y91221D01*
G01D02*
Y84533D01*
G01X935100Y112100D02*
X929800Y106800D01*
G01D02*
Y105900D01*
G01X911000Y105961D02*
Y114500D01*
G01X931078Y114466D02*
X924350Y107738D01*
G01D02*
Y102822D01*
G01D02*
X923750Y102222D01*
G01D02*
Y96755D01*
G01D02*
X922600Y95605D01*
G01D02*
Y84311D01*
G01X907908Y85090D02*
Y89401D01*
G01D02*
X917750Y99243D01*
G01D02*
Y102222D01*
G01D02*
X919000Y103472D01*
G01D02*
Y115338D01*
G01X914750Y101414D02*
Y102222D01*
G01D02*
X916217Y103689D01*
G01D02*
Y113700D01*
G01X917500Y116214D02*
Y103245D01*
G01D02*
X916250Y101995D01*
G01D02*
Y99865D01*
G01X914900Y113500D02*
Y103686D01*
G01X908243Y148343D02*
Y107243D01*
G01X924100Y83100D02*
Y94983D01*
G01D02*
X925250Y96133D01*
G01D02*
Y104850D01*
G01D02*
X931000Y110600D01*
G01X923450Y109729D02*
Y103422D01*
G01D02*
X922250Y102222D01*
G01D02*
Y97377D01*
G01D02*
X921100Y96227D01*
G01D02*
Y84933D01*
G01X926700Y117900D02*
Y114500D01*
G01D02*
X922000Y109800D01*
G01X922500Y114500D02*
X920400Y112400D01*
G01X935100Y113800D02*
Y112100D01*
G01X918890Y117604D02*
X917500Y116214D01*
G01X927921Y114200D02*
X923450Y109729D01*
G01X909843Y155512D02*
Y149943D01*
G01D02*
X908243Y148343D01*
G01X975650Y12186D02*
X960628Y-2836D01*
G01X964940Y-11435D02*
X971573Y-4802D01*
G01D02*
X1013541D01*
G01X1017068Y-9803D02*
X973884D01*
G01D02*
X967252Y-16435D01*
G01X952965Y25800D02*
X963269Y36104D01*
G01D02*
X1018609D01*
G01X1019853Y33104D02*
X968852D01*
G01D02*
X958819Y23071D01*
G01D02*
X954480D01*
G01D02*
X954209Y22800D01*
G01X958511Y20528D02*
X969140Y31157D01*
G01D02*
X1025165D01*
G01X1017987Y37604D02*
X962647D01*
G01D02*
X952343Y27300D01*
G01X953587Y24300D02*
X963891Y34604D01*
G01D02*
X1019231D01*
G01X956445Y75800D02*
X953895Y73250D01*
G01D02*
X951733D01*
G01D02*
X950019Y74964D01*
G01X959300Y72000D02*
X960099Y72799D01*
G01D02*
X962543D01*
G01D02*
X970497Y80753D01*
G01X959300Y68600D02*
X957450Y70450D01*
G01D02*
Y72900D01*
G01D02*
X958850Y74300D01*
G01X964105Y62308D02*
X960700Y58903D01*
G01D02*
X959470D01*
G01D02*
X959116Y59257D01*
G01D02*
X959088D01*
G01D02*
X958100Y60245D01*
G01X958655Y62350D02*
X959855Y61150D01*
G01D02*
Y61107D01*
G01X962200Y110140D02*
Y105644D01*
G01D02*
X965700Y102144D01*
G01D02*
Y95136D01*
G01D02*
X965846Y94990D01*
G01D02*
Y80346D01*
G01D02*
X961300Y75800D01*
G01D02*
X956445D01*
G01X950019Y74964D02*
X949102D01*
G01X948200Y79200D02*
X960436D01*
G01D02*
X962826Y81590D01*
G01D02*
Y93766D01*
G01D02*
X959200Y97392D01*
G01D02*
Y109400D01*
G01X970497Y80753D02*
Y152238D01*
G01X948822Y77700D02*
X961058D01*
G01D02*
X964326Y80968D01*
G01D02*
Y94388D01*
G01D02*
X960700Y98014D01*
G01D02*
Y110300D01*
G01X958850Y74300D02*
X961922D01*
G01D02*
X967346Y79724D01*
G01D02*
Y95612D01*
G01D02*
X967201Y95757D01*
G01D02*
Y141299D01*
G01X949893Y106378D02*
X950227D01*
G01D02*
X952400Y108551D01*
G01X964960Y131890D02*
Y130460D01*
G01D02*
X963300Y128800D01*
G01D02*
Y111240D01*
G01D02*
X962200Y110140D01*
G01X959200Y109400D02*
X955486Y113114D01*
G01D02*
Y128616D01*
G01D02*
X957159Y130289D01*
G01D02*
X957748D01*
G01D02*
X959200Y131741D01*
G01D02*
Y132330D01*
G01D02*
X961097Y134227D01*
G01D02*
X961686D01*
G01D02*
X962623Y135164D01*
G01D02*
Y137427D01*
G01D02*
X964960Y139764D01*
G01X960700Y110300D02*
X959423Y111577D01*
G01D02*
Y128616D01*
G01D02*
X961097Y130290D01*
G01D02*
X961686D01*
G01D02*
X963100Y131704D01*
G01D02*
Y133100D01*
G01D02*
X964960Y134960D01*
G01D02*
Y135827D01*
G01X967201Y141299D02*
X964960Y143540D01*
G01X949828Y109778D02*
Y124172D01*
G01D02*
X947500Y126500D01*
G01D02*
Y128700D01*
G01D02*
X951488Y132688D01*
G01D02*
X951500D01*
G01D02*
X952812Y134000D01*
G01D02*
X953900D01*
G01D02*
X954749Y134849D01*
G01D02*
Y149238D01*
G01X952400Y108551D02*
Y111000D01*
G01D02*
X951549Y111851D01*
G01D02*
Y128849D01*
G01D02*
X952990Y130290D01*
G01D02*
X953812D01*
G01D02*
X954749Y131227D01*
G01D02*
Y131449D01*
G01D02*
X954900Y131600D01*
G01D02*
Y133127D01*
G01D02*
X956000Y134227D01*
G01D02*
X957749D01*
G01D02*
X958686Y135164D01*
G01D02*
Y137427D01*
G01D02*
X961023Y139764D01*
G01X970497Y152238D02*
X968897Y153838D01*
G01D02*
Y155512D01*
G01X964960Y143540D02*
Y143701D01*
G01X954749Y149238D02*
X957086Y151575D01*
G01X994650Y39880D02*
Y43317D01*
G01X1025006Y22863D02*
X999563D01*
G01D02*
X988886Y12186D01*
G01D02*
X975650D01*
G01X994650Y43317D02*
X996130Y44797D01*
G01D02*
X1011921D01*
G01X1013541Y-4802D02*
X1019393Y1050D01*
G01D02*
X1043460D01*
G01X1046750Y-4122D02*
X1034437Y-16435D01*
G01D02*
X1023700D01*
G01D02*
X1017068Y-9803D01*
G01X1048423Y18527D02*
X1029342D01*
G01D02*
X1025006Y22863D01*
G01X1018609Y36104D02*
X1022698Y40193D01*
G01D02*
X1028152D01*
G01D02*
X1031419Y43460D01*
G01X1033017Y14743D02*
X1033022D01*
G01D02*
X1033179Y14900D01*
G01D02*
X1045141D01*
G01X1033554Y30216D02*
X1033223Y30547D01*
G01D02*
Y32378D01*
G01D02*
X1028667Y36934D01*
G01D02*
X1023683D01*
G01D02*
X1019853Y33104D01*
G01X1025165Y31157D02*
X1028403Y27919D01*
G01D02*
X1031929D01*
G01D02*
X1034828Y25020D01*
G01D02*
X1042872D01*
G01X1022118Y41735D02*
X1017987Y37604D01*
G01X1019231Y34604D02*
X1023061Y38434D01*
G01D02*
X1029746D01*
G01D02*
X1035545Y32635D01*
G01D02*
Y30827D01*
G01D02*
X1037072Y29300D01*
G01D02*
X1043565D01*
G01X1011921Y44797D02*
X1028167Y61043D01*
G01D02*
X1040241D01*
G01X1031419Y43460D02*
Y50661D01*
G01D02*
X1036567Y55809D01*
G01D02*
X1047410D01*
G01X1054757Y49640D02*
X1039384D01*
G01D02*
X1036854Y47110D01*
G01X1048032Y57309D02*
X1035688D01*
G01D02*
X1029919Y51540D01*
G01D02*
Y44295D01*
G01D02*
X1027359Y41735D01*
G01D02*
X1022118D01*
G01X1043460Y1050D02*
X1043632Y878D01*
G01D02*
X1048068D01*
G01D02*
X1048240Y1050D01*
G01D02*
X1081600D01*
G01X1072800Y-800D02*
X1072700Y-900D01*
G01D02*
Y-7100D01*
G01D02*
X1071500Y-8300D01*
G01D02*
X1062518D01*
G01D02*
X1058259Y-4041D01*
G01D02*
X1050222D01*
G01D02*
X1050141Y-4122D01*
G01D02*
X1046750D01*
G01X1082191Y26809D02*
X1065073D01*
G01D02*
X1062544Y29338D01*
G01D02*
X1059234D01*
G01D02*
X1048423Y18527D01*
G01X1045141Y14900D02*
X1046662Y13379D01*
G01D02*
X1051004D01*
G01D02*
X1051833Y12550D01*
G01D02*
X1058350D01*
G01D02*
X1060800Y10100D01*
G01X1042872Y25020D02*
X1047472Y29620D01*
G01D02*
Y34903D01*
G01D02*
X1052936Y40367D01*
G01D02*
Y41104D01*
G01X1043565Y29300D02*
X1044050Y28815D01*
G01X1047500Y41500D02*
X1050880Y44880D01*
G01D02*
X1052119D01*
G01D02*
X1056295Y49056D01*
G01D02*
X1061761D01*
G01D02*
X1063720Y51015D01*
G01D02*
X1066206D01*
G01D02*
X1080859Y51014D01*
G01X1091504Y49514D02*
X1065585D01*
G01D02*
X1064342Y49515D01*
G01D02*
X1062382Y47555D01*
G01D02*
X1056916D01*
G01D02*
X1051000Y41639D01*
G01D02*
Y41500D01*
G01X1047410Y55809D02*
X1049470Y53749D01*
G01X1052936Y41104D02*
X1057887Y46055D01*
G01D02*
X1063004D01*
G01D02*
X1063787Y46838D01*
G01D02*
X1077951D01*
G01X1140232Y121431D02*
X1072815Y54014D01*
G01D02*
X1064597D01*
G01D02*
X1061139Y50556D01*
G01D02*
X1055673D01*
G01D02*
X1054757Y49640D01*
G01X1049772Y57259D02*
X1048082D01*
G01D02*
X1048032Y57309D01*
G01X1081600Y1050D02*
X1082150Y500D01*
G01D02*
X1084000D01*
G01X1083500Y25500D02*
X1082191Y26809D01*
G01X1080859Y51014D02*
X1092829D01*
G01D02*
X1096843Y47000D01*
G01D02*
X1104622D01*
G01D02*
X1117272Y59650D01*
G01X1088287Y55917D02*
X1089730Y54474D01*
G01D02*
X1095974D01*
G01D02*
X1100448Y50000D01*
G01D02*
X1103378D01*
G01D02*
X1123181Y69803D01*
G01X1118150Y58150D02*
X1105500Y45500D01*
G01D02*
X1095518D01*
G01D02*
X1091504Y49514D01*
G01X1116950Y61450D02*
X1104000Y48500D01*
G01D02*
X1099222D01*
G01D02*
X1096496Y51226D01*
G01X1105441Y54768D02*
X1104300Y55909D01*
G01D02*
Y57000D01*
G01D02*
X1126552Y79252D01*
G01X1077951Y46838D02*
X1083379Y41410D01*
G01D02*
Y40889D01*
G01X1117272Y59650D02*
X1117528D01*
G01D02*
X1117529Y59651D01*
G01D02*
X1118771D01*
G01D02*
X1118772Y59650D01*
G01D02*
X1146472D01*
G01X1123181Y69803D02*
X1126513D01*
G01X1145850Y58150D02*
X1118150D01*
G01X1146794Y61450D02*
X1116950D01*
G01X1126552Y79252D02*
X1129466D01*
G01X1237732Y121431D02*
X1140232D01*
G01X1146472Y59650D02*
X1147122Y59000D01*
G01D02*
X1162378D01*
G01D02*
X1162928Y59550D01*
G01D02*
X1191072D01*
G01X1190450Y58050D02*
X1163550D01*
G01D02*
X1163000Y57500D01*
G01D02*
X1146500D01*
G01D02*
X1145850Y58150D01*
G01X1169820Y69803D02*
Y68320D01*
G01D02*
X1162500Y61000D01*
G01D02*
X1162256D01*
G01D02*
X1161756Y60500D01*
G01D02*
X1147744D01*
G01D02*
X1146794Y61450D01*
G01X1191072Y59550D02*
X1191623Y58999D01*
G01D02*
X1202324D01*
G01D02*
X1213128Y69803D01*
G01X1235000Y60500D02*
X1207500D01*
G01D02*
X1204000Y57000D01*
G01D02*
X1191500D01*
G01D02*
X1190450Y58050D01*
G01X1250500Y63000D02*
X1237500D01*
G01D02*
X1235000Y60500D01*
G01X1248097Y131796D02*
X1237732Y121431D01*
G01X1256435Y69803D02*
Y68935D01*
G01D02*
X1250500Y63000D01*
G01X1251801Y144765D02*
X1248097Y141061D01*
G01D02*
Y131796D01*
G01X1251801Y144871D02*
Y144765D01*
G54D12*
G01X-27072Y-83981D02*
Y-101481D01*
G01X-32094Y-83981D02*
X-22050D01*
G01X-13284Y-101481D02*
Y-83981D01*
G01Y-92439D02*
X-12192Y-90981D01*
X-11100Y-90106D01*
X-9354Y-89815D01*
X-8044Y-90106D01*
X-6515Y-91273D01*
X-5860Y-93023D01*
Y-101481D01*
G01X7928Y-89815D02*
Y-101481D01*
G01Y-85148D02*
X7491Y-84856D01*
Y-84273D01*
X7928Y-83981D01*
X8365Y-84273D01*
Y-84856D01*
X7928Y-85148D01*
G01X22153Y-99440D02*
X23245Y-100606D01*
X24773Y-101481D01*
X26083D01*
X27393Y-100898D01*
X28266Y-100023D01*
X28703Y-98857D01*
X28485Y-97106D01*
X27611Y-96231D01*
X23681Y-94481D01*
X22808Y-92439D01*
X23245Y-90981D01*
X24118Y-90106D01*
X25428Y-89815D01*
X26738Y-90106D01*
X28048Y-90981D01*
G01X57371Y-105856D02*
X58900Y-107023D01*
X60646Y-107314D01*
X62174Y-107023D01*
X63485Y-105565D01*
X64358Y-103523D01*
Y-89815D01*
G01Y-92148D02*
X63485Y-90981D01*
X62174Y-90106D01*
X60646Y-89815D01*
X58900Y-90398D01*
X57808Y-91564D01*
X56934Y-93606D01*
X56498Y-95648D01*
X56716Y-97398D01*
X57590Y-99440D01*
X58900Y-100898D01*
X60646Y-101481D01*
X61956Y-101189D01*
X63485Y-100023D01*
X64358Y-98857D01*
G01X74653Y-93606D02*
X81640D01*
X80985Y-91564D01*
X79893Y-90398D01*
X78365Y-89815D01*
X76836Y-90106D01*
X75526Y-90981D01*
X74653Y-93023D01*
X74216Y-94773D01*
Y-96523D01*
X74653Y-98273D01*
X75745Y-100023D01*
X77055Y-101189D01*
X78583Y-101481D01*
X80111Y-100898D01*
X81640Y-99148D01*
G01X92371Y-101481D02*
Y-89815D01*
G01Y-92148D02*
X93463Y-90981D01*
X94555Y-90106D01*
X96083Y-89815D01*
X97174Y-90106D01*
X98485Y-90981D01*
G01X108998Y-101481D02*
Y-83981D01*
G01Y-92731D02*
X110090Y-90981D01*
X111400Y-90106D01*
X112710Y-89815D01*
X114674Y-90398D01*
X115985Y-91564D01*
X116858Y-93606D01*
Y-95939D01*
X116421Y-98273D01*
X115548Y-100023D01*
X114020Y-101189D01*
X112710Y-101481D01*
X111400Y-101189D01*
X110090Y-100315D01*
X108998Y-98857D01*
G01X127153Y-93606D02*
X134140D01*
X133485Y-91564D01*
X132393Y-90398D01*
X130865Y-89815D01*
X129336Y-90106D01*
X128026Y-90981D01*
X127153Y-93023D01*
X126716Y-94773D01*
Y-96523D01*
X127153Y-98273D01*
X128245Y-100023D01*
X129555Y-101189D01*
X131083Y-101481D01*
X132611Y-100898D01*
X134140Y-99148D01*
G01X144871Y-101481D02*
Y-89815D01*
G01Y-92148D02*
X145963Y-90981D01*
X147055Y-90106D01*
X148583Y-89815D01*
X149674Y-90106D01*
X150985Y-90981D01*
G01X182928Y-89815D02*
Y-101481D01*
G01Y-85148D02*
X182491Y-84856D01*
Y-84273D01*
X182928Y-83981D01*
X183365Y-84273D01*
Y-84856D01*
X182928Y-85148D01*
G01X197153Y-99440D02*
X198245Y-100606D01*
X199773Y-101481D01*
X201083D01*
X202393Y-100898D01*
X203266Y-100023D01*
X203703Y-98857D01*
X203485Y-97106D01*
X202611Y-96231D01*
X198681Y-94481D01*
X197808Y-92439D01*
X198245Y-90981D01*
X199118Y-90106D01*
X200428Y-89815D01*
X201738Y-90106D01*
X203048Y-90981D01*
G01X231934Y-105856D02*
X233463Y-107023D01*
X234773Y-107314D01*
X236520Y-106731D01*
X237830Y-105273D01*
X238485Y-102647D01*
Y-89815D01*
G01Y-85148D02*
X238048Y-84856D01*
Y-84273D01*
X238485Y-83981D01*
X238921Y-84273D01*
Y-84856D01*
X238485Y-85148D01*
G01X249216Y-89815D02*
Y-97981D01*
X250090Y-100023D01*
X251400Y-101189D01*
X252928Y-101481D01*
X254456Y-101189D01*
X255766Y-100023D01*
X256640Y-97981D01*
G01Y-101481D02*
Y-89815D01*
G01X267153Y-99440D02*
X268245Y-100606D01*
X269773Y-101481D01*
X271083D01*
X272393Y-100898D01*
X273266Y-100023D01*
X273703Y-98857D01*
X273485Y-97106D01*
X272611Y-96231D01*
X268681Y-94481D01*
X267808Y-92439D01*
X268245Y-90981D01*
X269118Y-90106D01*
X270428Y-89815D01*
X271738Y-90106D01*
X273048Y-90981D01*
G01X287928Y-83981D02*
Y-101481D01*
G01X284871Y-89815D02*
X290985D01*
G01X321618Y-101481D02*
Y-86606D01*
X322055Y-85148D01*
X322928Y-84273D01*
X324238Y-83981D01*
X325548Y-84564D01*
X326203Y-86023D01*
G01X323583Y-90981D02*
X319216D01*
G01X340428Y-101481D02*
X339118Y-101189D01*
X337808Y-100023D01*
X336934Y-97981D01*
X336498Y-95648D01*
X336934Y-93314D01*
X337808Y-91273D01*
X339118Y-90106D01*
X340428Y-89815D01*
X341738Y-90106D01*
X343048Y-91273D01*
X343921Y-93314D01*
X344140Y-95648D01*
X343921Y-97981D01*
X343048Y-100023D01*
X341738Y-101189D01*
X340428Y-101481D01*
G01X354871D02*
Y-89815D01*
G01Y-92148D02*
X355963Y-90981D01*
X357055Y-90106D01*
X358583Y-89815D01*
X359674Y-90106D01*
X360985Y-90981D01*
G01X388343Y-106731D02*
X389653Y-107314D01*
X391400Y-106731D01*
X392491Y-105565D01*
X393365Y-104106D01*
X394674Y-99440D01*
X397513Y-89815D01*
G01X390526D02*
X394674Y-99440D01*
G01X410428Y-101481D02*
X409118Y-101189D01*
X407808Y-100023D01*
X406934Y-97981D01*
X406498Y-95648D01*
X406934Y-93314D01*
X407808Y-91273D01*
X409118Y-90106D01*
X410428Y-89815D01*
X411738Y-90106D01*
X413048Y-91273D01*
X413921Y-93314D01*
X414140Y-95648D01*
X413921Y-97981D01*
X413048Y-100023D01*
X411738Y-101189D01*
X410428Y-101481D01*
G01X424216Y-89815D02*
Y-97981D01*
X425090Y-100023D01*
X426400Y-101189D01*
X427928Y-101481D01*
X429456Y-101189D01*
X430766Y-100023D01*
X431640Y-97981D01*
G01Y-101481D02*
Y-89815D01*
G01X442371Y-101481D02*
Y-89815D01*
G01Y-92148D02*
X443463Y-90981D01*
X444555Y-90106D01*
X446083Y-89815D01*
X447174Y-90106D01*
X448485Y-90981D01*
G01X477371Y-101481D02*
Y-89815D01*
G01Y-92148D02*
X478463Y-90981D01*
X479555Y-90106D01*
X481083Y-89815D01*
X482174Y-90106D01*
X483485Y-90981D01*
G01X494653Y-93606D02*
X501640D01*
X500985Y-91564D01*
X499893Y-90398D01*
X498365Y-89815D01*
X496836Y-90106D01*
X495526Y-90981D01*
X494653Y-93023D01*
X494216Y-94773D01*
Y-96523D01*
X494653Y-98273D01*
X495745Y-100023D01*
X497055Y-101189D01*
X498583Y-101481D01*
X500111Y-100898D01*
X501640Y-99148D01*
G01X514118Y-101481D02*
Y-86606D01*
X514555Y-85148D01*
X515428Y-84273D01*
X516738Y-83981D01*
X518048Y-84564D01*
X518703Y-86023D01*
G01X516083Y-90981D02*
X511716D01*
G01X529653Y-93606D02*
X536640D01*
X535985Y-91564D01*
X534893Y-90398D01*
X533365Y-89815D01*
X531836Y-90106D01*
X530526Y-90981D01*
X529653Y-93023D01*
X529216Y-94773D01*
Y-96523D01*
X529653Y-98273D01*
X530745Y-100023D01*
X532055Y-101189D01*
X533583Y-101481D01*
X535111Y-100898D01*
X536640Y-99148D01*
G01X547371Y-101481D02*
Y-89815D01*
G01Y-92148D02*
X548463Y-90981D01*
X549555Y-90106D01*
X551083Y-89815D01*
X552174Y-90106D01*
X553485Y-90981D01*
G01X564653Y-93606D02*
X571640D01*
X570985Y-91564D01*
X569893Y-90398D01*
X568365Y-89815D01*
X566836Y-90106D01*
X565526Y-90981D01*
X564653Y-93023D01*
X564216Y-94773D01*
Y-96523D01*
X564653Y-98273D01*
X565745Y-100023D01*
X567055Y-101189D01*
X568583Y-101481D01*
X570111Y-100898D01*
X571640Y-99148D01*
G01X581716Y-101481D02*
Y-89815D01*
G01Y-92731D02*
X582590Y-91273D01*
X583900Y-90106D01*
X585646Y-89815D01*
X587174Y-90106D01*
X588485Y-91273D01*
X589140Y-93314D01*
Y-101481D01*
G01X606421Y-91273D02*
X604893Y-90106D01*
X603583Y-89815D01*
X601836Y-90398D01*
X600526Y-91564D01*
X599653Y-93606D01*
X599434Y-95648D01*
X599653Y-97690D01*
X600526Y-99440D01*
X601836Y-100898D01*
X603583Y-101481D01*
X605111Y-100898D01*
X606421Y-99731D01*
G01X617153Y-93606D02*
X624140D01*
X623485Y-91564D01*
X622393Y-90398D01*
X620865Y-89815D01*
X619336Y-90106D01*
X618026Y-90981D01*
X617153Y-93023D01*
X616716Y-94773D01*
Y-96523D01*
X617153Y-98273D01*
X618245Y-100023D01*
X619555Y-101189D01*
X621083Y-101481D01*
X622611Y-100898D01*
X624140Y-99148D01*
G01X655428Y-83981D02*
Y-101481D01*
G01X652371Y-89815D02*
X658485D01*
G01X672928Y-101481D02*
X671618Y-101189D01*
X670308Y-100023D01*
X669434Y-97981D01*
X668998Y-95648D01*
X669434Y-93314D01*
X670308Y-91273D01*
X671618Y-90106D01*
X672928Y-89815D01*
X674238Y-90106D01*
X675548Y-91273D01*
X676421Y-93314D01*
X676640Y-95648D01*
X676421Y-97981D01*
X675548Y-100023D01*
X674238Y-101189D01*
X672928Y-101481D01*
G01X706618D02*
Y-86606D01*
X707055Y-85148D01*
X707928Y-84273D01*
X709238Y-83981D01*
X710548Y-84564D01*
X711203Y-86023D01*
G01X708583Y-90981D02*
X704216D01*
G01X725428Y-89815D02*
Y-101481D01*
G01Y-85148D02*
X724991Y-84856D01*
Y-84273D01*
X725428Y-83981D01*
X725865Y-84273D01*
Y-84856D01*
X725428Y-85148D01*
G01X739216Y-101481D02*
Y-89815D01*
G01Y-92731D02*
X740090Y-91273D01*
X741400Y-90106D01*
X743146Y-89815D01*
X744674Y-90106D01*
X745985Y-91273D01*
X746640Y-93314D01*
Y-101481D01*
G01X764358Y-83981D02*
Y-101481D01*
G01Y-98857D02*
X763485Y-100315D01*
X762174Y-101189D01*
X760646Y-101481D01*
X758900Y-100898D01*
X757590Y-99440D01*
X756716Y-97690D01*
X756498Y-95648D01*
X756716Y-93606D01*
X757590Y-91856D01*
X758900Y-90398D01*
X760646Y-89815D01*
X762174Y-90106D01*
X763266Y-90690D01*
X764358Y-91856D01*
G01X795428Y-83981D02*
Y-101481D01*
G01X792371Y-89815D02*
X798485D01*
G01X809216Y-101481D02*
Y-83981D01*
G01Y-92439D02*
X810308Y-90981D01*
X811400Y-90106D01*
X813146Y-89815D01*
X814456Y-90106D01*
X815985Y-91273D01*
X816640Y-93023D01*
Y-101481D01*
G01X827153Y-93606D02*
X834140D01*
X833485Y-91564D01*
X832393Y-90398D01*
X830865Y-89815D01*
X829336Y-90106D01*
X828026Y-90981D01*
X827153Y-93023D01*
X826716Y-94773D01*
Y-96523D01*
X827153Y-98273D01*
X828245Y-100023D01*
X829555Y-101189D01*
X831083Y-101481D01*
X832611Y-100898D01*
X834140Y-99148D01*
G01X860843D02*
X862590Y-100606D01*
X864555Y-101481D01*
X866301D01*
X868048Y-100606D01*
X869358Y-99148D01*
X870013Y-97106D01*
X869576Y-95065D01*
X868485Y-93314D01*
X866520Y-92148D01*
X863900Y-91564D01*
X862371Y-90398D01*
X861716Y-88356D01*
X862153Y-86314D01*
X863245Y-84856D01*
X864773Y-83981D01*
X866301D01*
X867830Y-84564D01*
X869140Y-86023D01*
G01X887295Y-101481D02*
X878561D01*
Y-83981D01*
X887295D01*
G01X883801Y-92439D02*
X878561D01*
G01X917928Y-89815D02*
Y-101481D01*
G01Y-85148D02*
X917491Y-84856D01*
Y-84273D01*
X917928Y-83981D01*
X918365Y-84273D01*
Y-84856D01*
X917928Y-85148D01*
G01X928878Y-101481D02*
Y-89815D01*
G01Y-93023D02*
X929533Y-91564D01*
X930625Y-90398D01*
X932153Y-89815D01*
X933681Y-90398D01*
X934773Y-91564D01*
X935428Y-93023D01*
Y-101481D01*
G01Y-93023D02*
X936083Y-91564D01*
X937174Y-90398D01*
X938703Y-89815D01*
X940231Y-90398D01*
X941323Y-91564D01*
X941978Y-93314D01*
Y-101481D01*
G01X948998Y-107314D02*
Y-89815D01*
G01Y-92439D02*
X950090Y-90981D01*
X951181Y-90106D01*
X952928Y-89815D01*
X954456Y-90106D01*
X955985Y-91564D01*
X956640Y-93606D01*
X956858Y-95648D01*
X956640Y-97690D01*
X955985Y-99731D01*
X954674Y-100898D01*
X952928Y-101481D01*
X951400Y-101189D01*
X949871Y-100315D01*
X948998Y-99148D01*
G01X967153Y-93606D02*
X974140D01*
X973485Y-91564D01*
X972393Y-90398D01*
X970865Y-89815D01*
X969336Y-90106D01*
X968026Y-90981D01*
X967153Y-93023D01*
X966716Y-94773D01*
Y-96523D01*
X967153Y-98273D01*
X968245Y-100023D01*
X969555Y-101189D01*
X971083Y-101481D01*
X972611Y-100898D01*
X974140Y-99148D01*
G01X991858Y-83981D02*
Y-101481D01*
G01Y-98857D02*
X990985Y-100315D01*
X989674Y-101189D01*
X988146Y-101481D01*
X986400Y-100898D01*
X985090Y-99440D01*
X984216Y-97690D01*
X983998Y-95648D01*
X984216Y-93606D01*
X985090Y-91856D01*
X986400Y-90398D01*
X988146Y-89815D01*
X989674Y-90106D01*
X990766Y-90690D01*
X991858Y-91856D01*
G01X1009358Y-101481D02*
Y-89815D01*
G01Y-91856D02*
X1008485Y-90690D01*
X1007174Y-90106D01*
X1005646Y-89815D01*
X1004118Y-90398D01*
X1002808Y-91564D01*
X1001934Y-93314D01*
X1001498Y-95648D01*
X1001934Y-97981D01*
X1002808Y-99731D01*
X1004118Y-100898D01*
X1005646Y-101481D01*
X1007174Y-101189D01*
X1008485Y-100315D01*
X1009358Y-99148D01*
G01X1019216Y-101481D02*
Y-89815D01*
G01Y-92731D02*
X1020090Y-91273D01*
X1021400Y-90106D01*
X1023146Y-89815D01*
X1024674Y-90106D01*
X1025985Y-91273D01*
X1026640Y-93314D01*
Y-101481D01*
G01X1043921Y-91273D02*
X1042393Y-90106D01*
X1041083Y-89815D01*
X1039336Y-90398D01*
X1038026Y-91564D01*
X1037153Y-93606D01*
X1036934Y-95648D01*
X1037153Y-97690D01*
X1038026Y-99440D01*
X1039336Y-100898D01*
X1041083Y-101481D01*
X1042611Y-100898D01*
X1043921Y-99731D01*
G01X1054653Y-93606D02*
X1061640D01*
X1060985Y-91564D01*
X1059893Y-90398D01*
X1058365Y-89815D01*
X1056836Y-90106D01*
X1055526Y-90981D01*
X1054653Y-93023D01*
X1054216Y-94773D01*
Y-96523D01*
X1054653Y-98273D01*
X1055745Y-100023D01*
X1057055Y-101189D01*
X1058583Y-101481D01*
X1060111Y-100898D01*
X1061640Y-99148D01*
G01X1092928Y-83981D02*
Y-101481D01*
G01X1089871Y-89815D02*
X1095985D01*
G01X1107371Y-101481D02*
Y-89815D01*
G01Y-92148D02*
X1108463Y-90981D01*
X1109555Y-90106D01*
X1111083Y-89815D01*
X1112174Y-90106D01*
X1113485Y-90981D01*
G01X1131858Y-101481D02*
Y-89815D01*
G01Y-91856D02*
X1130985Y-90690D01*
X1129674Y-90106D01*
X1128146Y-89815D01*
X1126618Y-90398D01*
X1125308Y-91564D01*
X1124434Y-93314D01*
X1123998Y-95648D01*
X1124434Y-97981D01*
X1125308Y-99731D01*
X1126618Y-100898D01*
X1128146Y-101481D01*
X1129674Y-101189D01*
X1130985Y-100315D01*
X1131858Y-99148D01*
G01X1148921Y-91273D02*
X1147393Y-90106D01*
X1146083Y-89815D01*
X1144336Y-90398D01*
X1143026Y-91564D01*
X1142153Y-93606D01*
X1141934Y-95648D01*
X1142153Y-97690D01*
X1143026Y-99440D01*
X1144336Y-100898D01*
X1146083Y-101481D01*
X1147611Y-100898D01*
X1148921Y-99731D01*
G01X1159653Y-93606D02*
X1166640D01*
X1165985Y-91564D01*
X1164893Y-90398D01*
X1163365Y-89815D01*
X1161836Y-90106D01*
X1160526Y-90981D01*
X1159653Y-93023D01*
X1159216Y-94773D01*
Y-96523D01*
X1159653Y-98273D01*
X1160745Y-100023D01*
X1162055Y-101189D01*
X1163583Y-101481D01*
X1165111Y-100898D01*
X1166640Y-99148D01*
G01X1177153Y-99440D02*
X1178245Y-100606D01*
X1179773Y-101481D01*
X1181083D01*
X1182393Y-100898D01*
X1183266Y-100023D01*
X1183703Y-98857D01*
X1183485Y-97106D01*
X1182611Y-96231D01*
X1178681Y-94481D01*
X1177808Y-92439D01*
X1178245Y-90981D01*
X1179118Y-90106D01*
X1180428Y-89815D01*
X1181738Y-90106D01*
X1183048Y-90981D01*
G01X1215428Y-89815D02*
Y-101481D01*
G01Y-85148D02*
X1214991Y-84856D01*
Y-84273D01*
X1215428Y-83981D01*
X1215865Y-84273D01*
Y-84856D01*
X1215428Y-85148D01*
G01X1229216Y-101481D02*
Y-89815D01*
G01Y-92731D02*
X1230090Y-91273D01*
X1231400Y-90106D01*
X1233146Y-89815D01*
X1234674Y-90106D01*
X1235985Y-91273D01*
X1236640Y-93314D01*
Y-101481D01*
G01X1267928D02*
Y-83981D01*
G01X1289358Y-101481D02*
Y-89815D01*
G01Y-91856D02*
X1288485Y-90690D01*
X1287174Y-90106D01*
X1285646Y-89815D01*
X1284118Y-90398D01*
X1282808Y-91564D01*
X1281934Y-93314D01*
X1281498Y-95648D01*
X1281934Y-97981D01*
X1282808Y-99731D01*
X1284118Y-100898D01*
X1285646Y-101481D01*
X1287174Y-101189D01*
X1288485Y-100315D01*
X1289358Y-99148D01*
G01X1298343Y-106731D02*
X1299653Y-107314D01*
X1301400Y-106731D01*
X1302491Y-105565D01*
X1303365Y-104106D01*
X1304674Y-99440D01*
X1307513Y-89815D01*
G01X1300526D02*
X1304674Y-99440D01*
G01X1317153Y-93606D02*
X1324140D01*
X1323485Y-91564D01*
X1322393Y-90398D01*
X1320865Y-89815D01*
X1319336Y-90106D01*
X1318026Y-90981D01*
X1317153Y-93023D01*
X1316716Y-94773D01*
Y-96523D01*
X1317153Y-98273D01*
X1318245Y-100023D01*
X1319555Y-101189D01*
X1321083Y-101481D01*
X1322611Y-100898D01*
X1324140Y-99148D01*
G01X1334871Y-101481D02*
Y-89815D01*
G01Y-92148D02*
X1335963Y-90981D01*
X1337055Y-90106D01*
X1338583Y-89815D01*
X1339674Y-90106D01*
X1340985Y-90981D01*
G01X1368561Y-83981D02*
Y-101481D01*
X1377295D01*
G01X1386280Y-94190D02*
X1387808Y-92148D01*
X1389118Y-90981D01*
X1390865Y-90398D01*
X1392393Y-90981D01*
X1393485Y-92148D01*
X1394358Y-93898D01*
X1394576Y-95939D01*
X1394358Y-97690D01*
X1393485Y-99440D01*
X1392174Y-100898D01*
X1390646Y-101481D01*
X1388900Y-100898D01*
X1387371Y-99148D01*
X1386498Y-96523D01*
X1386280Y-93606D01*
X1386716Y-89815D01*
X1387371Y-87772D01*
X1388463Y-85731D01*
X1389991Y-84273D01*
X1391520Y-83981D01*
X1393048Y-84564D01*
X1394140Y-86023D01*
G01X1407928Y-102064D02*
X1407491Y-101773D01*
Y-101189D01*
X1407928Y-100898D01*
X1408365Y-101189D01*
Y-101773D01*
X1407928Y-102064D01*
G01X1481935Y875371D02*
X1483682Y873913D01*
X1485647Y873038D01*
X1487393D01*
X1489140Y873913D01*
X1490450Y875371D01*
X1491105Y877413D01*
X1490668Y879454D01*
X1489577Y881205D01*
X1487612Y882371D01*
X1484992Y882955D01*
X1483463Y884121D01*
X1482808Y886163D01*
X1483245Y888205D01*
X1484337Y889663D01*
X1485865Y890538D01*
X1487393D01*
X1488922Y889955D01*
X1490232Y888496D01*
G01X1508387Y873038D02*
X1499653D01*
Y890538D01*
X1508387D01*
G01X1504893Y882080D02*
X1499653D01*
G01X1536400Y890538D02*
X1541640D01*
G01X1539020D02*
Y873038D01*
G01X1536400D02*
X1541640D01*
G01X1550843D02*
Y890538D01*
X1556520Y875955D01*
X1562197Y890538D01*
Y873038D01*
G01X1569653D02*
Y890538D01*
X1574893D01*
X1576640Y889663D01*
X1577950Y887621D01*
X1578387Y885288D01*
X1577950Y882955D01*
X1576858Y881205D01*
X1574893Y880329D01*
X1569653D01*
G01X1595887Y873038D02*
X1587153D01*
Y890538D01*
X1595887D01*
G01X1592393Y882080D02*
X1587153D01*
G01X1604217Y873038D02*
Y890538D01*
X1608583D01*
X1610330Y889663D01*
X1611640Y888496D01*
X1612732Y886747D01*
X1613605Y884704D01*
X1613823Y881788D01*
X1613605Y878871D01*
X1612732Y876829D01*
X1611640Y875079D01*
X1610330Y873913D01*
X1608583Y873038D01*
X1604217D01*
G01X1621061D02*
X1626520Y890538D01*
X1631979Y873038D01*
G01X1630013Y879163D02*
X1623026D01*
G01X1638998Y873038D02*
Y890538D01*
X1649042Y873038D01*
Y890538D01*
G01X1666323Y889079D02*
X1665013Y889955D01*
X1663485Y890538D01*
X1661738D01*
X1659773Y889663D01*
X1658245Y888205D01*
X1657153Y886454D01*
X1656280Y883538D01*
X1656061Y880913D01*
X1656498Y878288D01*
X1657153Y876538D01*
X1658463Y874788D01*
X1659992Y873621D01*
X1661520Y873038D01*
X1663048D01*
X1664577Y873621D01*
X1665887Y874496D01*
X1666979Y875662D01*
G01X1683387Y873038D02*
X1674653D01*
Y890538D01*
X1683387D01*
G01X1679893Y882080D02*
X1674653D01*
G01X1714020Y890538D02*
Y873038D01*
G01X1708998Y890538D02*
X1719042D01*
G01X1726061Y873038D02*
X1731520Y890538D01*
X1736979Y873038D01*
G01X1735013Y879163D02*
X1728026D01*
G01X1750766Y882371D02*
X1751640Y883246D01*
X1752295Y884704D01*
X1752732Y886747D01*
X1752295Y888496D01*
X1751422Y889663D01*
X1749893Y890538D01*
X1743998D01*
Y873038D01*
X1751203D01*
X1752732Y874204D01*
X1753605Y875955D01*
X1754042Y877996D01*
X1753605Y880038D01*
X1752295Y881788D01*
X1750766Y882371D01*
X1743998D01*
G01X1762153Y890538D02*
Y873038D01*
X1770887D01*
G01X1788387D02*
X1779653D01*
Y890538D01*
X1788387D01*
G01X1784893Y882080D02*
X1779653D01*
G01X1801520Y872455D02*
X1801083Y872746D01*
Y873330D01*
X1801520Y873621D01*
X1801957Y873330D01*
Y872746D01*
X1801520Y872455D01*
G01Y880329D02*
X1801083Y880621D01*
Y881205D01*
X1801520Y881496D01*
X1801957Y881205D01*
Y880621D01*
X1801520Y880329D01*
G01X1832153Y890538D02*
Y873038D01*
X1840887D01*
G01X1849872Y880329D02*
X1851400Y882371D01*
X1852710Y883538D01*
X1854457Y884121D01*
X1855985Y883538D01*
X1857077Y882371D01*
X1857950Y880621D01*
X1858168Y878580D01*
X1857950Y876829D01*
X1857077Y875079D01*
X1855766Y873621D01*
X1854238Y873038D01*
X1852492Y873621D01*
X1850963Y875371D01*
X1850090Y877996D01*
X1849872Y880913D01*
X1850308Y884704D01*
X1850963Y886747D01*
X1852055Y888788D01*
X1853583Y890246D01*
X1855112Y890538D01*
X1856640Y889955D01*
X1857732Y888496D01*
G01X1503600Y855888D02*
X1508840D01*
G01X1506220D02*
Y838388D01*
G01X1503600D02*
X1508840D01*
G01X1518043D02*
Y855888D01*
X1523720Y841305D01*
X1529397Y855888D01*
Y838388D01*
G01X1536853D02*
Y855888D01*
X1542093D01*
X1543840Y855013D01*
X1545150Y852971D01*
X1545587Y850638D01*
X1545150Y848305D01*
X1544058Y846555D01*
X1542093Y845679D01*
X1536853D01*
G01X1557628Y832555D02*
X1555445Y835471D01*
X1554353Y838388D01*
Y850054D01*
X1555445Y852971D01*
X1557628Y855888D01*
G01X1576220Y838388D02*
X1574473Y838680D01*
X1572945Y839846D01*
X1571635Y841596D01*
X1570761Y843638D01*
X1570325Y845971D01*
Y848305D01*
X1570761Y850638D01*
X1571635Y852680D01*
X1572945Y854429D01*
X1574473Y855596D01*
X1576220Y855888D01*
X1577966Y855596D01*
X1579495Y854429D01*
X1580805Y852680D01*
X1581679Y850638D01*
X1582115Y848305D01*
Y845971D01*
X1581679Y843638D01*
X1580805Y841596D01*
X1579495Y839846D01*
X1577966Y838680D01*
X1576220Y838388D01*
G01X1590008D02*
Y855888D01*
G01Y847430D02*
X1591100Y848888D01*
X1592192Y849763D01*
X1593938Y850054D01*
X1595248Y849763D01*
X1596777Y848596D01*
X1597432Y846846D01*
Y838388D01*
G01X1604670D02*
Y850054D01*
G01Y846846D02*
X1605325Y848305D01*
X1606417Y849471D01*
X1607945Y850054D01*
X1609473Y849471D01*
X1610565Y848305D01*
X1611220Y846846D01*
Y838388D01*
G01Y846846D02*
X1611875Y848305D01*
X1612966Y849471D01*
X1614495Y850054D01*
X1616023Y849471D01*
X1617115Y848305D01*
X1617770Y846555D01*
Y838388D01*
G01X1629812Y832555D02*
X1631995Y835471D01*
X1633087Y838388D01*
Y850054D01*
X1631995Y852971D01*
X1629812Y855888D01*
G01X1536417Y806362D02*
X1537726Y804904D01*
X1539255Y804030D01*
X1541220Y803738D01*
X1543185Y804321D01*
X1544713Y805488D01*
X1545805Y807529D01*
X1546023Y809863D01*
X1545587Y812196D01*
X1544495Y813655D01*
X1542966Y814821D01*
X1541438Y815113D01*
X1539910Y814821D01*
X1537945Y813655D01*
X1538600Y821238D01*
X1544495D01*
G01X1558720D02*
X1556973Y820655D01*
X1555663Y819196D01*
X1554790Y817447D01*
X1554135Y815113D01*
X1553917Y812488D01*
X1554135Y809863D01*
X1554790Y807529D01*
X1555663Y805779D01*
X1556973Y804321D01*
X1558720Y803738D01*
X1560466Y804321D01*
X1561777Y805779D01*
X1562650Y807529D01*
X1563305Y809863D01*
X1563523Y812488D01*
X1563305Y815113D01*
X1562650Y817447D01*
X1561777Y819196D01*
X1560466Y820655D01*
X1558720Y821238D01*
G01X1576220Y803155D02*
X1575783Y803446D01*
Y804030D01*
X1576220Y804321D01*
X1576657Y804030D01*
Y803446D01*
X1576220Y803155D01*
G01X1593720Y821238D02*
X1591973Y820655D01*
X1590663Y819196D01*
X1589790Y817447D01*
X1589135Y815113D01*
X1588917Y812488D01*
X1589135Y809863D01*
X1589790Y807529D01*
X1590663Y805779D01*
X1591973Y804321D01*
X1593720Y803738D01*
X1595466Y804321D01*
X1596777Y805779D01*
X1597650Y807529D01*
X1598305Y809863D01*
X1598523Y812488D01*
X1598305Y815113D01*
X1597650Y817447D01*
X1596777Y819196D01*
X1595466Y820655D01*
X1593720Y821238D01*
G01X1674670Y855888D02*
X1677726Y838388D01*
X1681220Y855888D01*
X1684713Y838388D01*
X1687770Y855888D01*
G01X1696100D02*
X1701340D01*
G01X1698720D02*
Y838388D01*
G01X1696100D02*
X1701340D01*
G01X1711417D02*
Y855888D01*
X1715783D01*
X1717530Y855013D01*
X1718840Y853846D01*
X1719932Y852097D01*
X1720805Y850054D01*
X1721023Y847138D01*
X1720805Y844221D01*
X1719932Y842179D01*
X1718840Y840429D01*
X1717530Y839263D01*
X1715783Y838388D01*
X1711417D01*
G01X1733720Y855888D02*
Y838388D01*
G01X1728698Y855888D02*
X1738742D01*
G01X1746635Y838388D02*
Y855888D01*
G01X1755805D02*
Y838388D01*
G01Y847138D02*
X1746635D01*
G01X1767628Y832555D02*
X1765445Y835471D01*
X1764353Y838388D01*
Y850054D01*
X1765445Y852971D01*
X1767628Y855888D01*
G01X1779670Y838388D02*
Y850054D01*
G01Y846846D02*
X1780325Y848305D01*
X1781417Y849471D01*
X1782945Y850054D01*
X1784473Y849471D01*
X1785565Y848305D01*
X1786220Y846846D01*
Y838388D01*
G01Y846846D02*
X1786875Y848305D01*
X1787966Y849471D01*
X1789495Y850054D01*
X1791023Y849471D01*
X1792115Y848305D01*
X1792770Y846555D01*
Y838388D01*
G01X1803720Y850054D02*
Y838388D01*
G01Y854721D02*
X1803283Y855013D01*
Y855596D01*
X1803720Y855888D01*
X1804157Y855596D01*
Y855013D01*
X1803720Y854721D01*
G01X1821220Y838388D02*
Y855888D01*
G01X1835445Y840429D02*
X1836537Y839263D01*
X1838065Y838388D01*
X1839375D01*
X1840685Y838971D01*
X1841558Y839846D01*
X1841995Y841012D01*
X1841777Y842763D01*
X1840903Y843638D01*
X1836973Y845388D01*
X1836100Y847430D01*
X1836537Y848888D01*
X1837410Y849763D01*
X1838720Y850054D01*
X1840030Y849763D01*
X1841340Y848888D01*
G01X1857312Y832555D02*
X1859495Y835471D01*
X1860587Y838388D01*
Y850054D01*
X1859495Y852971D01*
X1857312Y855888D01*
G01X1746417Y806362D02*
X1747726Y804904D01*
X1749255Y804030D01*
X1751220Y803738D01*
X1753185Y804321D01*
X1754713Y805488D01*
X1755805Y807529D01*
X1756023Y809863D01*
X1755587Y812196D01*
X1754495Y813655D01*
X1752966Y814821D01*
X1751438Y815113D01*
X1749910Y814821D01*
X1747945Y813655D01*
X1748600Y821238D01*
X1754495D01*
G01X1768720Y803155D02*
X1768283Y803446D01*
Y804030D01*
X1768720Y804321D01*
X1769157Y804030D01*
Y803446D01*
X1768720Y803155D01*
G01X1786220Y821238D02*
X1784473Y820655D01*
X1783163Y819196D01*
X1782290Y817447D01*
X1781635Y815113D01*
X1781417Y812488D01*
X1781635Y809863D01*
X1782290Y807529D01*
X1783163Y805779D01*
X1784473Y804321D01*
X1786220Y803738D01*
X1787966Y804321D01*
X1789277Y805779D01*
X1790150Y807529D01*
X1790805Y809863D01*
X1791023Y812488D01*
X1790805Y815113D01*
X1790150Y817447D01*
X1789277Y819196D01*
X1787966Y820655D01*
X1786220Y821238D01*
G01X1908720Y855888D02*
Y838388D01*
G01X1903698Y855888D02*
X1913742D01*
G01X1926220Y838388D02*
Y846263D01*
X1921853Y855888D01*
G01X1930587D02*
X1926220Y846263D01*
G01X1939353Y838388D02*
Y855888D01*
X1944593D01*
X1946340Y855013D01*
X1947650Y852971D01*
X1948087Y850638D01*
X1947650Y848305D01*
X1946558Y846555D01*
X1944593Y845679D01*
X1939353D01*
G01X1965587Y838388D02*
X1956853D01*
Y855888D01*
X1965587D01*
G01X1962093Y847430D02*
X1956853D01*
G01X1921635Y806071D02*
X1923382Y804613D01*
X1925347Y803738D01*
X1927093D01*
X1928840Y804613D01*
X1930150Y806071D01*
X1930805Y808113D01*
X1930368Y810154D01*
X1929277Y811905D01*
X1927312Y813071D01*
X1924692Y813655D01*
X1923163Y814821D01*
X1922508Y816863D01*
X1922945Y818905D01*
X1924037Y820363D01*
X1925565Y821238D01*
X1927093D01*
X1928622Y820655D01*
X1929932Y819196D01*
G01X1948087Y803738D02*
X1939353D01*
Y821238D01*
X1948087D01*
G01X1944593Y812780D02*
X1939353D01*
G01X2009353Y838388D02*
Y855888D01*
X2014812D01*
X2016558Y855013D01*
X2017650Y853846D01*
X2018087Y851513D01*
X2017650Y849179D01*
X2016340Y847721D01*
X2014812Y846846D01*
X2009353D01*
G01X2014812D02*
X2018087Y838388D01*
G01X2027945Y846263D02*
X2034932D01*
X2034277Y848305D01*
X2033185Y849471D01*
X2031657Y850054D01*
X2030128Y849763D01*
X2028818Y848888D01*
X2027945Y846846D01*
X2027508Y845096D01*
Y843346D01*
X2027945Y841596D01*
X2029037Y839846D01*
X2030347Y838680D01*
X2031875Y838388D01*
X2033403Y838971D01*
X2034932Y840721D01*
G01X2047410Y838388D02*
Y853263D01*
X2047847Y854721D01*
X2048720Y855596D01*
X2050030Y855888D01*
X2051340Y855305D01*
X2051995Y853846D01*
G01X2049375Y848888D02*
X2045008D01*
G01X2066220Y837805D02*
X2065783Y838096D01*
Y838680D01*
X2066220Y838971D01*
X2066657Y838680D01*
Y838096D01*
X2066220Y837805D01*
G01X2096853Y838388D02*
Y855888D01*
X2102093D01*
X2103840Y855013D01*
X2105150Y852971D01*
X2105587Y850638D01*
X2105150Y848305D01*
X2104058Y846555D01*
X2102093Y845679D01*
X2096853D01*
G01X2118720Y838388D02*
Y855888D01*
G01X2140150Y838388D02*
Y850054D01*
G01Y848013D02*
X2139277Y849179D01*
X2137966Y849763D01*
X2136438Y850054D01*
X2134910Y849471D01*
X2133600Y848305D01*
X2132726Y846555D01*
X2132290Y844221D01*
X2132726Y841888D01*
X2133600Y840138D01*
X2134910Y838971D01*
X2136438Y838388D01*
X2137966Y838680D01*
X2139277Y839554D01*
X2140150Y840721D01*
G01X2150008Y838388D02*
Y850054D01*
G01Y847138D02*
X2150882Y848596D01*
X2152192Y849763D01*
X2153938Y850054D01*
X2155466Y849763D01*
X2156777Y848596D01*
X2157432Y846555D01*
Y838388D01*
G01X2167945Y846263D02*
X2174932D01*
X2174277Y848305D01*
X2173185Y849471D01*
X2171657Y850054D01*
X2170128Y849763D01*
X2168818Y848888D01*
X2167945Y846846D01*
X2167508Y845096D01*
Y843346D01*
X2167945Y841596D01*
X2169037Y839846D01*
X2170347Y838680D01*
X2171875Y838388D01*
X2173403Y838971D01*
X2174932Y840721D01*
G01X2053103Y821238D02*
Y803738D01*
X2061837D01*
G01X2070167Y806362D02*
X2071476Y804904D01*
X2073005Y804030D01*
X2074970Y803738D01*
X2076935Y804321D01*
X2078463Y805488D01*
X2079555Y807529D01*
X2079773Y809863D01*
X2079337Y812196D01*
X2078245Y813655D01*
X2076716Y814821D01*
X2075188Y815113D01*
X2073660Y814821D01*
X2071695Y813655D01*
X2072350Y821238D01*
X2078245D01*
G01X2088540Y803155D02*
X2096400Y821238D01*
G01X2105603D02*
Y803738D01*
X2114337D01*
G01X2127033D02*
X2127470Y807529D01*
X2128125Y810738D01*
X2128998Y813655D01*
X2130090Y816863D01*
X2131837Y821238D01*
X2123103D01*
G01X2289020Y815404D02*
Y803738D01*
G01Y820071D02*
X2288583Y820363D01*
Y820946D01*
X2289020Y821238D01*
X2289457Y820946D01*
Y820363D01*
X2289020Y820071D01*
G01X2303245Y805779D02*
X2304337Y804613D01*
X2305865Y803738D01*
X2307175D01*
X2308485Y804321D01*
X2309358Y805196D01*
X2309795Y806362D01*
X2309577Y808113D01*
X2308703Y808988D01*
X2304773Y810738D01*
X2303900Y812780D01*
X2304337Y814238D01*
X2305210Y815113D01*
X2306520Y815404D01*
X2307830Y815113D01*
X2309140Y814238D01*
G01X2336498Y803738D02*
Y821238D01*
X2346542Y803738D01*
Y821238D01*
G01X2359020Y803738D02*
X2357273Y804030D01*
X2355745Y805196D01*
X2354435Y806946D01*
X2353561Y808988D01*
X2353125Y811321D01*
Y813655D01*
X2353561Y815988D01*
X2354435Y818030D01*
X2355745Y819779D01*
X2357273Y820946D01*
X2359020Y821238D01*
X2360766Y820946D01*
X2362295Y819779D01*
X2363605Y818030D01*
X2364479Y815988D01*
X2364915Y813655D01*
Y811321D01*
X2364479Y808988D01*
X2363605Y806946D01*
X2362295Y805196D01*
X2360766Y804030D01*
X2359020Y803738D01*
G01X2376520Y821238D02*
Y803738D01*
G01X2371498Y821238D02*
X2381542D01*
G01X2407808Y815404D02*
Y807238D01*
X2408682Y805196D01*
X2409992Y804030D01*
X2411520Y803738D01*
X2413048Y804030D01*
X2414358Y805196D01*
X2415232Y807238D01*
G01Y803738D02*
Y815404D01*
G01X2425745Y805779D02*
X2426837Y804613D01*
X2428365Y803738D01*
X2429675D01*
X2430985Y804321D01*
X2431858Y805196D01*
X2432295Y806362D01*
X2432077Y808113D01*
X2431203Y808988D01*
X2427273Y810738D01*
X2426400Y812780D01*
X2426837Y814238D01*
X2427710Y815113D01*
X2429020Y815404D01*
X2430330Y815113D01*
X2431640Y814238D01*
G01X2443245Y811613D02*
X2450232D01*
X2449577Y813655D01*
X2448485Y814821D01*
X2446957Y815404D01*
X2445428Y815113D01*
X2444118Y814238D01*
X2443245Y812196D01*
X2442808Y810446D01*
Y808696D01*
X2443245Y806946D01*
X2444337Y805196D01*
X2445647Y804030D01*
X2447175Y803738D01*
X2448703Y804321D01*
X2450232Y806071D01*
G01X2467950Y821238D02*
Y803738D01*
G01Y806362D02*
X2467077Y804904D01*
X2465766Y804030D01*
X2464238Y803738D01*
X2462492Y804321D01*
X2461182Y805779D01*
X2460308Y807529D01*
X2460090Y809571D01*
X2460308Y811613D01*
X2461182Y813363D01*
X2462492Y814821D01*
X2464238Y815404D01*
X2465766Y815113D01*
X2466858Y814529D01*
X2467950Y813363D01*
G01X2214217Y837805D02*
X2223823Y850638D01*
G01X2219020Y852971D02*
Y835471D01*
G01X2223823Y837805D02*
X2214217Y850638D01*
G01X2212470Y844221D02*
X2225570D01*
G01X2251182D02*
X2256858D01*
G01X2284217Y838388D02*
Y855888D01*
X2288583D01*
X2290330Y855013D01*
X2291640Y853846D01*
X2292732Y852097D01*
X2293605Y850054D01*
X2293823Y847138D01*
X2293605Y844221D01*
X2292732Y842179D01*
X2291640Y840429D01*
X2290330Y839263D01*
X2288583Y838388D01*
X2284217D01*
G01X2303245Y846263D02*
X2310232D01*
X2309577Y848305D01*
X2308485Y849471D01*
X2306957Y850054D01*
X2305428Y849763D01*
X2304118Y848888D01*
X2303245Y846846D01*
X2302808Y845096D01*
Y843346D01*
X2303245Y841596D01*
X2304337Y839846D01*
X2305647Y838680D01*
X2307175Y838388D01*
X2308703Y838971D01*
X2310232Y840721D01*
G01X2320308Y838388D02*
Y850054D01*
G01Y847138D02*
X2321182Y848596D01*
X2322492Y849763D01*
X2324238Y850054D01*
X2325766Y849763D01*
X2327077Y848596D01*
X2327732Y846555D01*
Y838388D01*
G01X2341520D02*
X2340210Y838680D01*
X2338900Y839846D01*
X2338026Y841888D01*
X2337590Y844221D01*
X2338026Y846555D01*
X2338900Y848596D01*
X2340210Y849763D01*
X2341520Y850054D01*
X2342830Y849763D01*
X2344140Y848596D01*
X2345013Y846555D01*
X2345232Y844221D01*
X2345013Y841888D01*
X2344140Y839846D01*
X2342830Y838680D01*
X2341520Y838388D01*
G01X2359020Y855888D02*
Y838388D01*
G01X2355963Y850054D02*
X2362077D01*
G01X2373245Y846263D02*
X2380232D01*
X2379577Y848305D01*
X2378485Y849471D01*
X2376957Y850054D01*
X2375428Y849763D01*
X2374118Y848888D01*
X2373245Y846846D01*
X2372808Y845096D01*
Y843346D01*
X2373245Y841596D01*
X2374337Y839846D01*
X2375647Y838680D01*
X2377175Y838388D01*
X2378703Y838971D01*
X2380232Y840721D01*
G01X2390745Y840429D02*
X2391837Y839263D01*
X2393365Y838388D01*
X2394675D01*
X2395985Y838971D01*
X2396858Y839846D01*
X2397295Y841012D01*
X2397077Y842763D01*
X2396203Y843638D01*
X2392273Y845388D01*
X2391400Y847430D01*
X2391837Y848888D01*
X2392710Y849763D01*
X2394020Y850054D01*
X2395330Y849763D01*
X2396640Y848888D01*
G01X2429020Y855888D02*
Y838388D01*
G01X2425963Y850054D02*
X2432077D01*
G01X2442808Y838388D02*
Y855888D01*
G01Y847430D02*
X2443900Y848888D01*
X2444992Y849763D01*
X2446738Y850054D01*
X2448048Y849763D01*
X2449577Y848596D01*
X2450232Y846846D01*
Y838388D01*
G01X2467950D02*
Y850054D01*
G01Y848013D02*
X2467077Y849179D01*
X2465766Y849763D01*
X2464238Y850054D01*
X2462710Y849471D01*
X2461400Y848305D01*
X2460526Y846555D01*
X2460090Y844221D01*
X2460526Y841888D01*
X2461400Y840138D01*
X2462710Y838971D01*
X2464238Y838388D01*
X2465766Y838680D01*
X2467077Y839554D01*
X2467950Y840721D01*
G01X2481520Y855888D02*
Y838388D01*
G01X2478463Y850054D02*
X2484577D01*
G01X2516520Y855888D02*
Y838388D01*
G01X2513463Y850054D02*
X2519577D01*
G01X2530308Y838388D02*
Y855888D01*
G01Y847430D02*
X2531400Y848888D01*
X2532492Y849763D01*
X2534238Y850054D01*
X2535548Y849763D01*
X2537077Y848596D01*
X2537732Y846846D01*
Y838388D01*
G01X2551520Y850054D02*
Y838388D01*
G01Y854721D02*
X2551083Y855013D01*
Y855596D01*
X2551520Y855888D01*
X2551957Y855596D01*
Y855013D01*
X2551520Y854721D01*
G01X2565745Y840429D02*
X2566837Y839263D01*
X2568365Y838388D01*
X2569675D01*
X2570985Y838971D01*
X2571858Y839846D01*
X2572295Y841012D01*
X2572077Y842763D01*
X2571203Y843638D01*
X2567273Y845388D01*
X2566400Y847430D01*
X2566837Y848888D01*
X2567710Y849763D01*
X2569020Y850054D01*
X2570330Y849763D01*
X2571640Y848888D01*
G01X2601400Y855888D02*
X2606640D01*
G01X2604020D02*
Y838388D01*
G01X2601400D02*
X2606640D01*
G01X2614970D02*
Y850054D01*
G01Y846846D02*
X2615625Y848305D01*
X2616717Y849471D01*
X2618245Y850054D01*
X2619773Y849471D01*
X2620865Y848305D01*
X2621520Y846846D01*
Y838388D01*
G01Y846846D02*
X2622175Y848305D01*
X2623266Y849471D01*
X2624795Y850054D01*
X2626323Y849471D01*
X2627415Y848305D01*
X2628070Y846555D01*
Y838388D01*
G01X2635090Y832555D02*
Y850054D01*
G01Y847430D02*
X2636182Y848888D01*
X2637273Y849763D01*
X2639020Y850054D01*
X2640548Y849763D01*
X2642077Y848305D01*
X2642732Y846263D01*
X2642950Y844221D01*
X2642732Y842179D01*
X2642077Y840138D01*
X2640766Y838971D01*
X2639020Y838388D01*
X2637492Y838680D01*
X2635963Y839554D01*
X2635090Y840721D01*
G01X2653245Y846263D02*
X2660232D01*
X2659577Y848305D01*
X2658485Y849471D01*
X2656957Y850054D01*
X2655428Y849763D01*
X2654118Y848888D01*
X2653245Y846846D01*
X2652808Y845096D01*
Y843346D01*
X2653245Y841596D01*
X2654337Y839846D01*
X2655647Y838680D01*
X2657175Y838388D01*
X2658703Y838971D01*
X2660232Y840721D01*
G01X2677950Y855888D02*
Y838388D01*
G01Y841012D02*
X2677077Y839554D01*
X2675766Y838680D01*
X2674238Y838388D01*
X2672492Y838971D01*
X2671182Y840429D01*
X2670308Y842179D01*
X2670090Y844221D01*
X2670308Y846263D01*
X2671182Y848013D01*
X2672492Y849471D01*
X2674238Y850054D01*
X2675766Y849763D01*
X2676858Y849179D01*
X2677950Y848013D01*
G01X2695450Y838388D02*
Y850054D01*
G01Y848013D02*
X2694577Y849179D01*
X2693266Y849763D01*
X2691738Y850054D01*
X2690210Y849471D01*
X2688900Y848305D01*
X2688026Y846555D01*
X2687590Y844221D01*
X2688026Y841888D01*
X2688900Y840138D01*
X2690210Y838971D01*
X2691738Y838388D01*
X2693266Y838680D01*
X2694577Y839554D01*
X2695450Y840721D01*
G01X2705308Y838388D02*
Y850054D01*
G01Y847138D02*
X2706182Y848596D01*
X2707492Y849763D01*
X2709238Y850054D01*
X2710766Y849763D01*
X2712077Y848596D01*
X2712732Y846555D01*
Y838388D01*
G01X2730013Y848596D02*
X2728485Y849763D01*
X2727175Y850054D01*
X2725428Y849471D01*
X2724118Y848305D01*
X2723245Y846263D01*
X2723026Y844221D01*
X2723245Y842179D01*
X2724118Y840429D01*
X2725428Y838971D01*
X2727175Y838388D01*
X2728703Y838971D01*
X2730013Y840138D01*
G01X2740745Y846263D02*
X2747732D01*
X2747077Y848305D01*
X2745985Y849471D01*
X2744457Y850054D01*
X2742928Y849763D01*
X2741618Y848888D01*
X2740745Y846846D01*
X2740308Y845096D01*
Y843346D01*
X2740745Y841596D01*
X2741837Y839846D01*
X2743147Y838680D01*
X2744675Y838388D01*
X2746203Y838971D01*
X2747732Y840721D01*
G01X1425733Y-51181D02*
X-29385D01*
G01X-33322Y-47244D02*
G03X-29385Y-51181I3937J0D01*
G01X-33322Y-47244D02*
Y893701D01*
G01X-7874Y102402D02*
Y212205D01*
G01Y102402D02*
G03X0Y94528I7874J0D01*
G01Y212205D02*
G03X-7874I-3937J0D01*
G01Y237402D02*
G03X0I3937J-1D01*
G01X-7874D02*
Y406693D01*
G01X0D02*
G03X-7874I-3937J0D01*
G01Y431890D02*
G03X0I3937J0D01*
G01X-7874D02*
Y601181D01*
G01X0D02*
G03X-7874I-3937J0D01*
G01Y626378D02*
Y795669D01*
G01Y626378D02*
G03X0I3937J0D01*
G01Y795669D02*
G03X-7874I-3937J0D01*
G01Y820866D02*
G03X0I3937J0D01*
G01X-7874Y844488D02*
Y820866D01*
G01X-3937Y848425D02*
G03X-7874Y844488I0J-3937D01*
G01X93307Y848425D02*
X-3937D01*
G01X-29385Y897638D02*
G03X-33322Y893701I0J-3937D01*
G01X-29385Y897638D02*
X93307D01*
G01X98425Y94528D02*
X0D01*
G01X1400000Y36220D02*
G03X1398031Y38189I-1969J0D01*
G01X1396654D01*
G02X1394685Y40157I0J1969D01*
G01Y71654D01*
G02X1396654Y73622I1969J-1D01*
G01X1398031D01*
G03X1400000Y75591I0J1969D01*
G01Y836614D01*
G03X1396063Y840551I-3937J0D01*
G01X1368504D01*
G02X1363386Y845669I0J5118D01*
G01Y871654D01*
G03X1361417Y873622I-1969J-1D01*
G01X1358268D01*
G02X1356299Y875591I0J1969D01*
G01Y892521D01*
X1352363Y897638D01*
X1218110D01*
X1214173Y892520D01*
Y875984D01*
G02X1205512I-4331J0D01*
G01Y892520D01*
X1201575Y897638D01*
X1029528D01*
X1025591Y892520D01*
Y875591D01*
G02X1023622Y873622I-1969J0D01*
G01X1020472D01*
G03X1018504Y871654I0J-1968D01*
G01Y845669D01*
G02X1013386Y840551I-5118J0D01*
G01X1008433D01*
G03X988748Y820866I0J-19685D01*
G01Y650669D01*
G02X983748Y645669I-5000J0D01*
G01X926819D01*
G02X921819Y650669I0J5000D01*
G01Y820866D01*
G03X902134Y840551I-19685J0D01*
G01X872441D01*
G02X867323Y845669I0J5118D01*
G01Y871654D01*
G03X865354Y873622I-1969J-1D01*
G01X862205D01*
G02X860236Y875591I0J1969D01*
G01Y892521D01*
X856300Y897638D01*
X722048D01*
X718110Y892519D01*
Y875984D01*
G02X709449I-4331J0D01*
G01Y892520D01*
X705512Y897638D01*
X533465D01*
X529528Y892520D01*
Y875591D01*
G02X527559Y873622I-1969J0D01*
G01X524409D01*
G03X522441Y871654I0J-1968D01*
G01Y845669D01*
G02X517323Y840551I-5118J0D01*
G01X455118D01*
G02X450000Y845669I0J5118D01*
G01Y871654D01*
G03X448031Y873622I-1968J0D01*
G01X444882D01*
G02X442913Y875591I0J1969D01*
G01Y892521D01*
X438977Y897638D01*
X304725D01*
X300787Y892519D01*
Y875984D01*
G02X292126I-4331J0D01*
G01Y892521D01*
X288190Y897638D01*
X116142D01*
X112205Y892520D01*
Y875591D01*
G02X110236Y873622I-1969J0D01*
G01X107087D01*
G03X105118Y871654I0J-1969D01*
G01Y845669D01*
G02X100000Y840551I-5118J0D01*
G01X3937D01*
G03X0Y836614I0J-3937D01*
G01Y110276D01*
G03X7874Y102402I7874J0D01*
G01X196654D01*
G02X204528Y94528I0J-7874D01*
G01Y7874D01*
G03X212402Y0I7874J0D01*
G01X471014D01*
G02X478888Y-7874I0J-7874D01*
G01Y-11811D01*
G03X486762Y-19685I7874J0D01*
G01X1302165D01*
G03X1306102Y-15748I0J3937D01*
G01Y-3937D01*
G02X1310039Y0I3937J0D01*
G01X1396063D01*
G03X1400000Y3937I0J3937D01*
G01Y36220D01*
G01X93307Y848425D02*
G03X97244Y852362I0J3937D01*
G01Y893701D02*
Y852362D01*
G01Y893701D02*
G03X93307Y897638I-3937J0D01*
G01X192717Y94528D02*
X123622D01*
G01Y102402D02*
G03Y94528I0J-3937D01*
G01X98425D02*
G03Y102402I0J3937D01*
G01X196654Y0D02*
G03X204528Y-7874I7874J0D01*
G01X196654Y0D02*
Y29961D01*
G01X204528D02*
G03X196654I-3937J0D01*
G01Y55157D02*
Y90591D01*
G01Y55157D02*
G03X204528I3937J0D01*
G01X196654Y90591D02*
G03X192717Y94528I-3937J0D01*
G01X232077Y-7874D02*
G03Y0I0J3937D01*
G01Y-7874D02*
X204528D01*
G01X434439D02*
X257274D01*
G01Y0D02*
G03Y-7874I0J-3937D01*
G01X365945Y38188D02*
G03X367914Y40156I0J1969D01*
G01X354134D02*
G03X356103Y38188I1969J1D01*
G01D02*
X365945D01*
G01X354134Y71653D02*
Y40156D01*
G01X367914Y71653D02*
G03X365945Y73621I-1969J-1D01*
G01X356103D02*
G03X354134Y71653I0J-1969D01*
G01X365945Y73621D02*
X356103D01*
G01X367914Y40156D02*
Y71653D01*
G01X434439Y-7874D02*
G03Y0I0J3937D01*
G01X471014Y-15748D02*
G03X463140Y-7874I-7874J0D01*
G01D02*
X459636D01*
G01Y0D02*
G03Y-7874I0J-3937D01*
G01X707234Y-27559D02*
X478888D01*
G01X471014Y-19685D02*
G03X478888Y-27559I7874J0D01*
G01X471014Y-19685D02*
Y-15748D01*
G01X870226Y-27559D02*
X732431D01*
G01Y-19685D02*
G03Y-27559I0J-3937D01*
G01X707234D02*
G03Y-19685I0J3937D01*
G01X870226Y-27559D02*
G03Y-19685I1J3937D01*
G01X1072589Y-27559D02*
X895423D01*
G01Y-19685D02*
G03Y-27559I0J-3937D01*
G01X1072589D02*
G03Y-19685I0J3937D01*
G01X1097785D02*
G03Y-27559I1J-3937D01*
G01X1336086Y-8662D02*
X1318701D01*
G03X1314764Y-12599I0J-3937D01*
G01Y-23622D01*
G02X1310827Y-27559I-3937J0D01*
G01X1097785D01*
G01X1336086Y-8662D02*
G03Y-1I0J4330D01*
G01X1361283D02*
G03Y-8662I0J-4330D01*
G01X1407874Y13026D02*
Y-4725D01*
G02X1403937Y-8662I-3937J0D01*
G01X1361283D01*
G01X1403937Y848425D02*
X1375197D01*
G01X1371260Y852362D02*
G03X1375197Y848425I3937J0D01*
G01X1371260Y852362D02*
Y893701D01*
G01X1375197Y897638D02*
G03X1371260Y893701I0J-3937D01*
G01X1375197Y897638D02*
X1425733D01*
G01X1407874Y30709D02*
Y219685D01*
G01X1400000Y30709D02*
G03X1407874I3937J0D01*
G01Y13026D02*
G03X1400000I-3937J-1D01*
G01X1407874Y219685D02*
G03X1400000I-3937J0D01*
G01Y244882D02*
G03X1407874I3937J0D01*
G01Y414173D02*
Y244882D01*
G01Y608661D02*
Y439370D01*
G01X1400000D02*
G03X1407874I3937J0D01*
G01Y414173D02*
G03X1400000I-3937J0D01*
G01X1407874Y608661D02*
G03X1400000I-3937J0D01*
G01Y626378D02*
G03X1407874I3937J0D01*
G01Y795669D02*
Y626378D01*
G01Y795669D02*
G03X1400000I-3937J0D01*
G01Y820866D02*
G03X1407874I3937J0D01*
G01Y844488D02*
Y820866D01*
G01Y844488D02*
G03X1403937Y848425I-3937J0D01*
G01X1429670Y893701D02*
Y-47244D01*
G01X1425733Y-51181D02*
G03X1429670Y-47244I0J3937D01*
G01Y893701D02*
G03X1425733Y897638I-3937J0D01*
M02*
